FILE_TYPE = MACRO_DRAWING;
SET COLOR_WIRE YELLOW;
SET COLOR_PROP ORANGE;
SET COLOR_DOT WHITE;
SET COLOR_ARC YELLOW;
SET COLOR_BODY GREEN;
SET COLOR_NOTE PURPLE;
SET PROP_DISPLAY VALUE;
SET PAGE_NUMBER P73;
FORCEADD UNIVERSAL_GND..1
(-3050 -675);
FORCEPROP 3 LASTPIN (-3050 -625) SIG_NAME GND\g
J 0
(-3040 -615);
DISPLAY 0.659574 (-3040 -615);
PAINT MONO (-3040 -615);
DISPLAY INVISIBLE (-3040 -615);
FORCEPROP 2 LAST CDS_LIB logical_power
J 0
(-3050 -675);
PAINT MONO (-3050 -675);
DISPLAY INVISIBLE (-3050 -675);
FORCEPROP 1 LAST HDL_POWER GND
J 1
(-3025 -750);
DISPLAY 0.872340 (-3025 -750);
PAINT GREEN (-3025 -750);
DISPLAY INVISIBLE (-3025 -750);
FORCEPROP 1 LAST PATH I1
J 0
(-2975 -675);
DISPLAY 0.872340 (-2975 -675);
PAINT AQUA (-2975 -675);
DISPLAY INVISIBLE (-2975 -675);
FORCEADD SOCKET4677_AZIF0045P001C01CS..40
(-1600 1850);
FORCEPROP 1 LAST PART_NUMBER DGA^7000023
J 0
(-2650 4100);
DISPLAY 0.723404 (-2650 4100);
PAINT GREEN (-2650 4100);
DISPLAY INVISIBLE (-2650 4100);
FORCEPROP 2 LAST PART_TYPE SMLF
J 0
(-2650 4275);
DISPLAY 1.021277 (-2650 4275);
FORCEPROP 1 LAST MATERIAL IO
J 0
(-2650 4025);
DISPLAY 0.723404 (-2650 4025);
PAINT GREEN (-2650 4025);
FORCEPROP 2 LAST VALUE SOCKET4677_AZIF0045-P001C01CS
J 0
(-2650 4225);
DISPLAY 1.021277 (-2650 4225);
FORCEPROP 1 LAST $LOCATION U1
J 0
(-2650 4175);
DISPLAY 0.723404 (-2650 4175);
PAINT GREEN (-2650 4175);
FORCEPROP 0 LASTPIN (-2800 2825) $PN AA19
J 2
(-2810 2835);
DISPLAY 0.680851 (-2810 2835);
PAINT MONO (-2810 2835);
FORCEPROP 0 LASTPIN (-2800 2875) $PN AA23
J 2
(-2810 2885);
DISPLAY 0.680851 (-2810 2885);
PAINT MONO (-2810 2885);
FORCEPROP 0 LASTPIN (-2800 2925) $PN AA25
J 2
(-2810 2935);
DISPLAY 0.680851 (-2810 2935);
PAINT MONO (-2810 2935);
FORCEPROP 0 LASTPIN (-2800 2975) $PN AA29
J 2
(-2810 2985);
DISPLAY 0.680851 (-2810 2985);
PAINT MONO (-2810 2985);
FORCEPROP 0 LASTPIN (-2800 3025) $PN AA31
J 2
(-2810 3035);
DISPLAY 0.680851 (-2810 3035);
PAINT MONO (-2810 3035);
FORCEPROP 0 LASTPIN (-2800 3075) $PN AA35
J 2
(-2810 3085);
DISPLAY 0.680851 (-2810 3085);
PAINT MONO (-2810 3085);
FORCEPROP 0 LASTPIN (-2800 3125) $PN AA37
J 2
(-2810 3135);
DISPLAY 0.680851 (-2810 3135);
PAINT MONO (-2810 3135);
FORCEPROP 0 LASTPIN (-2800 3175) $PN AA41
J 2
(-2810 3185);
DISPLAY 0.680851 (-2810 3185);
PAINT MONO (-2810 3185);
FORCEPROP 0 LASTPIN (-2800 3225) $PN AA43
J 2
(-2810 3235);
DISPLAY 0.680851 (-2810 3235);
PAINT MONO (-2810 3235);
FORCEPROP 0 LASTPIN (-2800 3275) $PN AA48
J 2
(-2810 3285);
DISPLAY 0.680851 (-2810 3285);
PAINT MONO (-2810 3285);
FORCEPROP 0 LASTPIN (-2800 3325) $PN AA50
J 2
(-2810 3335);
DISPLAY 0.680851 (-2810 3335);
PAINT MONO (-2810 3335);
FORCEPROP 0 LASTPIN (-2800 3375) $PN AA54
J 2
(-2810 3385);
DISPLAY 0.680851 (-2810 3385);
PAINT MONO (-2810 3385);
FORCEPROP 0 LASTPIN (-2800 3425) $PN AA56
J 2
(-2810 3435);
DISPLAY 0.680851 (-2810 3435);
PAINT MONO (-2810 3435);
FORCEPROP 0 LASTPIN (-2800 3475) $PN AA60
J 2
(-2810 3485);
DISPLAY 0.680851 (-2810 3485);
PAINT MONO (-2810 3485);
FORCEPROP 0 LASTPIN (-2800 3525) $PN AA62
J 2
(-2810 3535);
DISPLAY 0.680851 (-2810 3535);
PAINT MONO (-2810 3535);
FORCEPROP 0 LASTPIN (-2800 3575) $PN AA66
J 2
(-2810 3585);
DISPLAY 0.680851 (-2810 3585);
PAINT MONO (-2810 3585);
FORCEPROP 0 LASTPIN (-2800 3625) $PN AA68
J 2
(-2810 3635);
DISPLAY 0.680851 (-2810 3635);
PAINT MONO (-2810 3635);
FORCEPROP 0 LASTPIN (-2800 3675) $PN AA72
J 2
(-2810 3685);
DISPLAY 0.680851 (-2810 3685);
PAINT MONO (-2810 3685);
FORCEPROP 0 LASTPIN (-2800 3725) $PN AA74
J 2
(-2810 3735);
DISPLAY 0.680851 (-2810 3735);
PAINT MONO (-2810 3735);
FORCEPROP 0 LASTPIN (-2800 3775) $PN AA78
J 2
(-2810 3785);
DISPLAY 0.680851 (-2810 3785);
PAINT MONO (-2810 3785);
FORCEPROP 0 LASTPIN (-2800 3825) $PN AA80
J 2
(-2810 3835);
DISPLAY 0.680851 (-2810 3835);
PAINT MONO (-2810 3835);
FORCEPROP 0 LASTPIN (-400 575) $PN P32
J 0
(-390 585);
DISPLAY 0.680851 (-390 585);
PAINT MONO (-390 585);
FORCEPROP 0 LASTPIN (-400 -125) $PN N76
J 0
(-390 -115);
DISPLAY 0.680851 (-390 -115);
PAINT MONO (-390 -115);
FORCEPROP 0 LASTPIN (-400 875) $PN P51
J 0
(-390 885);
DISPLAY 0.680851 (-390 885);
PAINT MONO (-390 885);
FORCEPROP 0 LASTPIN (-400 -75) $PN N78
J 0
(-390 -65);
DISPLAY 0.680851 (-390 -65);
PAINT MONO (-390 -65);
FORCEPROP 0 LASTPIN (-400 975) $PN P57
J 0
(-390 985);
DISPLAY 0.680851 (-390 985);
PAINT MONO (-390 985);
FORCEPROP 0 LASTPIN (-400 -25) $PN N80
J 0
(-390 -15);
DISPLAY 0.680851 (-390 -15);
PAINT MONO (-390 -15);
FORCEPROP 0 LASTPIN (-400 25) $PN N82
J 0
(-390 35);
DISPLAY 0.680851 (-390 35);
PAINT MONO (-390 35);
FORCEPROP 0 LASTPIN (-400 75) $PN N84
J 0
(-390 85);
DISPLAY 0.680851 (-390 85);
PAINT MONO (-390 85);
FORCEPROP 0 LASTPIN (-400 125) $PN N88
J 0
(-390 135);
DISPLAY 0.680851 (-390 135);
PAINT MONO (-390 135);
FORCEPROP 0 LASTPIN (-400 1225) $PN P71
J 0
(-390 1235);
DISPLAY 0.680851 (-390 1235);
PAINT MONO (-390 1235);
FORCEPROP 0 LASTPIN (-400 275) $PN P12
J 0
(-390 285);
DISPLAY 0.680851 (-390 285);
PAINT MONO (-390 285);
FORCEPROP 0 LASTPIN (-400 325) $PN P16
J 0
(-390 335);
DISPLAY 0.680851 (-390 335);
PAINT MONO (-390 335);
FORCEPROP 0 LASTPIN (-400 375) $PN P20
J 0
(-390 385);
DISPLAY 0.680851 (-390 385);
PAINT MONO (-390 385);
FORCEPROP 0 LASTPIN (-400 425) $PN P22
J 0
(-390 435);
DISPLAY 0.680851 (-390 435);
PAINT MONO (-390 435);
FORCEPROP 0 LASTPIN (-400 475) $PN P26
J 0
(-390 485);
DISPLAY 0.680851 (-390 485);
PAINT MONO (-390 485);
FORCEPROP 0 LASTPIN (-400 525) $PN P28
J 0
(-390 535);
DISPLAY 0.680851 (-390 535);
PAINT MONO (-390 535);
FORCEPROP 0 LASTPIN (-400 1475) $PN R1
J 0
(-390 1485);
DISPLAY 0.680851 (-390 1485);
PAINT MONO (-390 1485);
FORCEPROP 0 LASTPIN (-400 625) $PN P34
J 0
(-390 635);
DISPLAY 0.680851 (-390 635);
PAINT MONO (-390 635);
FORCEPROP 0 LASTPIN (-400 675) $PN P38
J 0
(-390 685);
DISPLAY 0.680851 (-390 685);
PAINT MONO (-390 685);
FORCEPROP 0 LASTPIN (-400 1725) $PN R19
J 0
(-390 1735);
DISPLAY 0.680851 (-390 1735);
PAINT MONO (-390 1735);
FORCEPROP 0 LASTPIN (-400 1775) $PN R23
J 0
(-390 1785);
DISPLAY 0.680851 (-390 1785);
PAINT MONO (-390 1785);
FORCEPROP 0 LASTPIN (-400 175) $PN P4
J 0
(-390 185);
DISPLAY 0.680851 (-390 185);
PAINT MONO (-390 185);
FORCEPROP 0 LASTPIN (-400 725) $PN P40
J 0
(-390 735);
DISPLAY 0.680851 (-390 735);
PAINT MONO (-390 735);
FORCEPROP 0 LASTPIN (-400 775) $PN P44
J 0
(-390 785);
DISPLAY 0.680851 (-390 785);
PAINT MONO (-390 785);
FORCEPROP 0 LASTPIN (-400 825) $PN P47
J 0
(-390 835);
DISPLAY 0.680851 (-390 835);
PAINT MONO (-390 835);
FORCEPROP 0 LASTPIN (-400 925) $PN P53
J 0
(-390 935);
DISPLAY 0.680851 (-390 935);
PAINT MONO (-390 935);
FORCEPROP 0 LASTPIN (-400 1025) $PN P59
J 0
(-390 1035);
DISPLAY 0.680851 (-390 1035);
PAINT MONO (-390 1035);
FORCEPROP 0 LASTPIN (-400 1075) $PN P63
J 0
(-390 1085);
DISPLAY 0.680851 (-390 1085);
PAINT MONO (-390 1085);
FORCEPROP 0 LASTPIN (-400 2175) $PN R48
J 0
(-390 2185);
DISPLAY 0.680851 (-390 2185);
PAINT MONO (-390 2185);
FORCEPROP 0 LASTPIN (-400 1125) $PN P65
J 0
(-390 1135);
DISPLAY 0.680851 (-390 1135);
PAINT MONO (-390 1135);
FORCEPROP 0 LASTPIN (-400 1175) $PN P69
J 0
(-390 1185);
DISPLAY 0.680851 (-390 1185);
PAINT MONO (-390 1185);
FORCEPROP 0 LASTPIN (-400 1275) $PN P75
J 0
(-390 1285);
DISPLAY 0.680851 (-390 1285);
PAINT MONO (-390 1285);
FORCEPROP 0 LASTPIN (-400 1325) $PN P77
J 0
(-390 1335);
DISPLAY 0.680851 (-390 1335);
PAINT MONO (-390 1335);
FORCEPROP 0 LASTPIN (-400 2375) $PN R60
J 0
(-390 2385);
DISPLAY 0.680851 (-390 2385);
PAINT MONO (-390 2385);
FORCEPROP 0 LASTPIN (-400 225) $PN P8
J 0
(-390 235);
DISPLAY 0.680851 (-390 235);
PAINT MONO (-390 235);
FORCEPROP 0 LASTPIN (-400 2475) $PN R66
J 0
(-390 2485);
DISPLAY 0.680851 (-390 2485);
PAINT MONO (-390 2485);
FORCEPROP 0 LASTPIN (-400 1375) $PN P87
J 0
(-390 1385);
DISPLAY 0.680851 (-390 1385);
PAINT MONO (-390 1385);
FORCEPROP 0 LASTPIN (-400 1425) $PN P91
J 0
(-390 1435);
DISPLAY 0.680851 (-390 1435);
PAINT MONO (-390 1435);
FORCEPROP 0 LASTPIN (-400 1625) $PN R13
J 0
(-390 1635);
DISPLAY 0.680851 (-390 1635);
PAINT MONO (-390 1635);
FORCEPROP 0 LASTPIN (-400 1675) $PN R17
J 0
(-390 1685);
DISPLAY 0.680851 (-390 1685);
PAINT MONO (-390 1685);
FORCEPROP 0 LASTPIN (-400 1825) $PN R25
J 0
(-390 1835);
DISPLAY 0.680851 (-390 1835);
PAINT MONO (-390 1835);
FORCEPROP 0 LASTPIN (-400 1875) $PN R29
J 0
(-390 1885);
DISPLAY 0.680851 (-390 1885);
PAINT MONO (-390 1885);
FORCEPROP 0 LASTPIN (-400 1925) $PN R31
J 0
(-390 1935);
DISPLAY 0.680851 (-390 1935);
PAINT MONO (-390 1935);
FORCEPROP 0 LASTPIN (-400 1975) $PN R35
J 0
(-390 1985);
DISPLAY 0.680851 (-390 1985);
PAINT MONO (-390 1985);
FORCEPROP 0 LASTPIN (-400 2925) $PN T12
J 0
(-390 2935);
DISPLAY 0.680851 (-390 2935);
PAINT MONO (-390 2935);
FORCEPROP 0 LASTPIN (-400 2975) $PN T16
J 0
(-390 2985);
DISPLAY 0.680851 (-390 2985);
PAINT MONO (-390 2985);
FORCEPROP 0 LASTPIN (-400 3025) $PN T18
J 0
(-390 3035);
DISPLAY 0.680851 (-390 3035);
PAINT MONO (-390 3035);
FORCEPROP 0 LASTPIN (-400 2025) $PN R37
J 0
(-390 2035);
DISPLAY 0.680851 (-390 2035);
PAINT MONO (-390 2035);
FORCEPROP 0 LASTPIN (-400 2075) $PN R41
J 0
(-390 2085);
DISPLAY 0.680851 (-390 2085);
PAINT MONO (-390 2085);
FORCEPROP 0 LASTPIN (-400 2125) $PN R43
J 0
(-390 2135);
DISPLAY 0.680851 (-390 2135);
PAINT MONO (-390 2135);
FORCEPROP 0 LASTPIN (-400 1525) $PN R5
J 0
(-390 1535);
DISPLAY 0.680851 (-390 1535);
PAINT MONO (-390 1535);
FORCEPROP 0 LASTPIN (-400 3175) $PN T36
J 0
(-390 3185);
DISPLAY 0.680851 (-390 3185);
PAINT MONO (-390 3185);
FORCEPROP 0 LASTPIN (-400 2225) $PN R50
J 0
(-390 2235);
DISPLAY 0.680851 (-390 2235);
PAINT MONO (-390 2235);
FORCEPROP 0 LASTPIN (-400 2275) $PN R54
J 0
(-390 2285);
DISPLAY 0.680851 (-390 2285);
PAINT MONO (-390 2285);
FORCEPROP 0 LASTPIN (-400 3275) $PN T49
J 0
(-390 3285);
DISPLAY 0.680851 (-390 3285);
PAINT MONO (-390 3285);
FORCEPROP 0 LASTPIN (-400 3325) $PN T55
J 0
(-390 3335);
DISPLAY 0.680851 (-390 3335);
PAINT MONO (-390 3335);
FORCEPROP 0 LASTPIN (-400 2325) $PN R56
J 0
(-390 2335);
DISPLAY 0.680851 (-390 2335);
PAINT MONO (-390 2335);
FORCEPROP 0 LASTPIN (-400 2425) $PN R62
J 0
(-390 2435);
DISPLAY 0.680851 (-390 2435);
PAINT MONO (-390 2435);
FORCEPROP 0 LASTPIN (-400 2525) $PN R68
J 0
(-390 2535);
DISPLAY 0.680851 (-390 2535);
PAINT MONO (-390 2535);
FORCEPROP 0 LASTPIN (-400 2575) $PN R72
J 0
(-390 2585);
DISPLAY 0.680851 (-390 2585);
PAINT MONO (-390 2585);
FORCEPROP 0 LASTPIN (-400 2625) $PN R74
J 0
(-390 2635);
DISPLAY 0.680851 (-390 2635);
PAINT MONO (-390 2635);
FORCEPROP 0 LASTPIN (-400 2675) $PN R78
J 0
(-390 2685);
DISPLAY 0.680851 (-390 2685);
PAINT MONO (-390 2685);
FORCEPROP 0 LASTPIN (-400 2725) $PN R84
J 0
(-390 2735);
DISPLAY 0.680851 (-390 2735);
PAINT MONO (-390 2735);
FORCEPROP 0 LASTPIN (-400 2775) $PN R88
J 0
(-390 2785);
DISPLAY 0.680851 (-390 2785);
PAINT MONO (-390 2785);
FORCEPROP 0 LASTPIN (-400 1575) $PN R9
J 0
(-390 1585);
DISPLAY 0.680851 (-390 1585);
PAINT MONO (-390 1585);
FORCEPROP 0 LASTPIN (-400 3075) $PN T24
J 0
(-390 3085);
DISPLAY 0.680851 (-390 3085);
PAINT MONO (-390 3085);
FORCEPROP 0 LASTPIN (-400 3125) $PN T30
J 0
(-390 3135);
DISPLAY 0.680851 (-390 3135);
PAINT MONO (-390 3135);
FORCEPROP 0 LASTPIN (-400 2825) $PN T4
J 0
(-390 2835);
DISPLAY 0.680851 (-390 2835);
PAINT MONO (-390 2835);
FORCEPROP 0 LASTPIN (-400 3225) $PN T42
J 0
(-390 3235);
DISPLAY 0.680851 (-390 3235);
PAINT MONO (-390 3235);
FORCEPROP 0 LASTPIN (-400 3375) $PN T61
J 0
(-390 3385);
DISPLAY 0.680851 (-390 3385);
PAINT MONO (-390 3385);
FORCEPROP 0 LASTPIN (-400 3425) $PN T67
J 0
(-390 3435);
DISPLAY 0.680851 (-390 3435);
PAINT MONO (-390 3435);
FORCEPROP 0 LASTPIN (-400 3675) $PN U52
J 0
(-390 3685);
DISPLAY 0.680851 (-390 3685);
PAINT MONO (-390 3685);
FORCEPROP 0 LASTPIN (-400 3475) $PN T73
J 0
(-390 3485);
DISPLAY 0.680851 (-390 3485);
PAINT MONO (-390 3485);
FORCEPROP 0 LASTPIN (-400 3525) $PN T79
J 0
(-390 3535);
DISPLAY 0.680851 (-390 3535);
PAINT MONO (-390 3535);
FORCEPROP 0 LASTPIN (-400 2875) $PN T8
J 0
(-390 2885);
DISPLAY 0.680851 (-390 2885);
PAINT MONO (-390 2885);
FORCEPROP 0 LASTPIN (-400 3575) $PN T83
J 0
(-390 3585);
DISPLAY 0.680851 (-390 3585);
PAINT MONO (-390 3585);
FORCEPROP 0 LASTPIN (-400 3625) $PN U39
J 0
(-390 3635);
DISPLAY 0.680851 (-390 3635);
PAINT MONO (-390 3635);
FORCEPROP 0 LASTPIN (-400 3725) $PN U82
J 0
(-390 3735);
DISPLAY 0.680851 (-390 3735);
PAINT MONO (-390 3735);
FORCEPROP 0 LASTPIN (-400 3775) $PN U84
J 0
(-390 3785);
DISPLAY 0.680851 (-390 3785);
PAINT MONO (-390 3785);
FORCEPROP 0 LASTPIN (-400 3825) $PN U88
J 0
(-390 3835);
DISPLAY 0.680851 (-390 3835);
PAINT MONO (-390 3835);
FORCEPROP 0 LASTPIN (-2800 -25) $PN V12
J 2
(-2810 -15);
DISPLAY 0.680851 (-2810 -15);
PAINT MONO (-2810 -15);
FORCEPROP 0 LASTPIN (-2800 25) $PN V16
J 2
(-2810 35);
DISPLAY 0.680851 (-2810 35);
PAINT MONO (-2810 35);
FORCEPROP 0 LASTPIN (-2800 75) $PN V18
J 2
(-2810 85);
DISPLAY 0.680851 (-2810 85);
PAINT MONO (-2810 85);
FORCEPROP 0 LASTPIN (-2800 125) $PN V20
J 2
(-2810 135);
DISPLAY 0.680851 (-2810 135);
PAINT MONO (-2810 135);
FORCEPROP 0 LASTPIN (-2800 175) $PN V22
J 2
(-2810 185);
DISPLAY 0.680851 (-2810 185);
PAINT MONO (-2810 185);
FORCEPROP 0 LASTPIN (-2800 225) $PN V24
J 2
(-2810 235);
DISPLAY 0.680851 (-2810 235);
PAINT MONO (-2810 235);
FORCEPROP 0 LASTPIN (-2800 275) $PN V26
J 2
(-2810 285);
DISPLAY 0.680851 (-2810 285);
PAINT MONO (-2810 285);
FORCEPROP 0 LASTPIN (-2800 325) $PN V28
J 2
(-2810 335);
DISPLAY 0.680851 (-2810 335);
PAINT MONO (-2810 335);
FORCEPROP 0 LASTPIN (-2800 375) $PN V30
J 2
(-2810 385);
DISPLAY 0.680851 (-2810 385);
PAINT MONO (-2810 385);
FORCEPROP 0 LASTPIN (-2800 425) $PN V32
J 2
(-2810 435);
DISPLAY 0.680851 (-2810 435);
PAINT MONO (-2810 435);
FORCEPROP 0 LASTPIN (-2800 475) $PN V34
J 2
(-2810 485);
DISPLAY 0.680851 (-2810 485);
PAINT MONO (-2810 485);
FORCEPROP 0 LASTPIN (-2800 525) $PN V36
J 2
(-2810 535);
DISPLAY 0.680851 (-2810 535);
PAINT MONO (-2810 535);
FORCEPROP 0 LASTPIN (-2800 575) $PN V38
J 2
(-2810 585);
DISPLAY 0.680851 (-2810 585);
PAINT MONO (-2810 585);
FORCEPROP 0 LASTPIN (-2800 -125) $PN V4
J 2
(-2810 -115);
DISPLAY 0.680851 (-2810 -115);
PAINT MONO (-2810 -115);
FORCEPROP 0 LASTPIN (-2800 825) $PN V49
J 2
(-2810 835);
DISPLAY 0.680851 (-2810 835);
PAINT MONO (-2810 835);
FORCEPROP 0 LASTPIN (-2800 625) $PN V40
J 2
(-2810 635);
DISPLAY 0.680851 (-2810 635);
PAINT MONO (-2810 635);
FORCEPROP 0 LASTPIN (-2800 675) $PN V42
J 2
(-2810 685);
DISPLAY 0.680851 (-2810 685);
PAINT MONO (-2810 685);
FORCEPROP 0 LASTPIN (-2800 725) $PN V44
J 2
(-2810 735);
DISPLAY 0.680851 (-2810 735);
PAINT MONO (-2810 735);
FORCEPROP 0 LASTPIN (-2800 775) $PN V47
J 2
(-2810 785);
DISPLAY 0.680851 (-2810 785);
PAINT MONO (-2810 785);
FORCEPROP 0 LASTPIN (-2800 875) $PN V51
J 2
(-2810 885);
DISPLAY 0.680851 (-2810 885);
PAINT MONO (-2810 885);
FORCEPROP 0 LASTPIN (-2800 925) $PN V53
J 2
(-2810 935);
DISPLAY 0.680851 (-2810 935);
PAINT MONO (-2810 935);
FORCEPROP 0 LASTPIN (-2800 975) $PN V55
J 2
(-2810 985);
DISPLAY 0.680851 (-2810 985);
PAINT MONO (-2810 985);
FORCEPROP 0 LASTPIN (-2800 1025) $PN V57
J 2
(-2810 1035);
DISPLAY 0.680851 (-2810 1035);
PAINT MONO (-2810 1035);
FORCEPROP 0 LASTPIN (-2800 1075) $PN V59
J 2
(-2810 1085);
DISPLAY 0.680851 (-2810 1085);
PAINT MONO (-2810 1085);
FORCEPROP 0 LASTPIN (-2800 1125) $PN V61
J 2
(-2810 1135);
DISPLAY 0.680851 (-2810 1135);
PAINT MONO (-2810 1135);
FORCEPROP 0 LASTPIN (-2800 1375) $PN V71
J 2
(-2810 1385);
DISPLAY 0.680851 (-2810 1385);
PAINT MONO (-2810 1385);
FORCEPROP 0 LASTPIN (-2800 1425) $PN V73
J 2
(-2810 1435);
DISPLAY 0.680851 (-2810 1435);
PAINT MONO (-2810 1435);
FORCEPROP 0 LASTPIN (-2800 1175) $PN V63
J 2
(-2810 1185);
DISPLAY 0.680851 (-2810 1185);
PAINT MONO (-2810 1185);
FORCEPROP 0 LASTPIN (-2800 1225) $PN V65
J 2
(-2810 1235);
DISPLAY 0.680851 (-2810 1235);
PAINT MONO (-2810 1235);
FORCEPROP 0 LASTPIN (-2800 1275) $PN V67
J 2
(-2810 1285);
DISPLAY 0.680851 (-2810 1285);
PAINT MONO (-2810 1285);
FORCEPROP 0 LASTPIN (-2800 1325) $PN V69
J 2
(-2810 1335);
DISPLAY 0.680851 (-2810 1335);
PAINT MONO (-2810 1335);
FORCEPROP 0 LASTPIN (-2800 1475) $PN V75
J 2
(-2810 1485);
DISPLAY 0.680851 (-2810 1485);
PAINT MONO (-2810 1485);
FORCEPROP 0 LASTPIN (-2800 1675) $PN V91
J 2
(-2810 1685);
DISPLAY 0.680851 (-2810 1685);
PAINT MONO (-2810 1685);
FORCEPROP 0 LASTPIN (-2800 1725) $PN W1
J 2
(-2810 1735);
DISPLAY 0.680851 (-2810 1735);
PAINT MONO (-2810 1735);
FORCEPROP 0 LASTPIN (-2800 1875) $PN W13
J 2
(-2810 1885);
DISPLAY 0.680851 (-2810 1885);
PAINT MONO (-2810 1885);
FORCEPROP 0 LASTPIN (-2800 1525) $PN V77
J 2
(-2810 1535);
DISPLAY 0.680851 (-2810 1535);
PAINT MONO (-2810 1535);
FORCEPROP 0 LASTPIN (-2800 1575) $PN V79
J 2
(-2810 1585);
DISPLAY 0.680851 (-2810 1585);
PAINT MONO (-2810 1585);
FORCEPROP 0 LASTPIN (-2800 -75) $PN V8
J 2
(-2810 -65);
DISPLAY 0.680851 (-2810 -65);
PAINT MONO (-2810 -65);
FORCEPROP 0 LASTPIN (-2800 1625) $PN V87
J 2
(-2810 1635);
DISPLAY 0.680851 (-2810 1635);
PAINT MONO (-2810 1635);
FORCEPROP 0 LASTPIN (-2800 1775) $PN W5
J 2
(-2810 1785);
DISPLAY 0.680851 (-2810 1785);
PAINT MONO (-2810 1785);
FORCEPROP 0 LASTPIN (-2800 1975) $PN W52
J 2
(-2810 1985);
DISPLAY 0.680851 (-2810 1985);
PAINT MONO (-2810 1985);
FORCEPROP 0 LASTPIN (-2800 1925) $PN W39
J 2
(-2810 1935);
DISPLAY 0.680851 (-2810 1935);
PAINT MONO (-2810 1935);
FORCEPROP 0 LASTPIN (-2800 2025) $PN W84
J 2
(-2810 2035);
DISPLAY 0.680851 (-2810 2035);
PAINT MONO (-2810 2035);
FORCEPROP 0 LASTPIN (-2800 2075) $PN W88
J 2
(-2810 2085);
DISPLAY 0.680851 (-2810 2085);
PAINT MONO (-2810 2085);
FORCEPROP 0 LASTPIN (-2800 1825) $PN W9
J 2
(-2810 1835);
DISPLAY 0.680851 (-2810 1835);
PAINT MONO (-2810 1835);
FORCEPROP 0 LASTPIN (-2800 2225) $PN Y12
J 2
(-2810 2235);
DISPLAY 0.680851 (-2810 2235);
PAINT MONO (-2810 2235);
FORCEPROP 0 LASTPIN (-2800 2275) $PN Y16
J 2
(-2810 2285);
DISPLAY 0.680851 (-2810 2285);
PAINT MONO (-2810 2285);
FORCEPROP 0 LASTPIN (-2800 2325) $PN Y18
J 2
(-2810 2335);
DISPLAY 0.680851 (-2810 2335);
PAINT MONO (-2810 2335);
FORCEPROP 0 LASTPIN (-2800 2375) $PN Y24
J 2
(-2810 2385);
DISPLAY 0.680851 (-2810 2385);
PAINT MONO (-2810 2385);
FORCEPROP 0 LASTPIN (-2800 2425) $PN Y30
J 2
(-2810 2435);
DISPLAY 0.680851 (-2810 2435);
PAINT MONO (-2810 2435);
FORCEPROP 0 LASTPIN (-2800 2475) $PN Y36
J 2
(-2810 2485);
DISPLAY 0.680851 (-2810 2485);
PAINT MONO (-2810 2485);
FORCEPROP 0 LASTPIN (-2800 2125) $PN Y4
J 2
(-2810 2135);
DISPLAY 0.680851 (-2810 2135);
PAINT MONO (-2810 2135);
FORCEPROP 0 LASTPIN (-2800 2525) $PN Y42
J 2
(-2810 2535);
DISPLAY 0.680851 (-2810 2535);
PAINT MONO (-2810 2535);
FORCEPROP 0 LASTPIN (-2800 2675) $PN Y61
J 2
(-2810 2685);
DISPLAY 0.680851 (-2810 2685);
PAINT MONO (-2810 2685);
FORCEPROP 0 LASTPIN (-2800 2725) $PN Y67
J 2
(-2810 2735);
DISPLAY 0.680851 (-2810 2735);
PAINT MONO (-2810 2735);
FORCEPROP 0 LASTPIN (-2800 2575) $PN Y49
J 2
(-2810 2585);
DISPLAY 0.680851 (-2810 2585);
PAINT MONO (-2810 2585);
FORCEPROP 0 LASTPIN (-2800 2625) $PN Y55
J 2
(-2810 2635);
DISPLAY 0.680851 (-2810 2635);
PAINT MONO (-2810 2635);
FORCEPROP 0 LASTPIN (-2800 2175) $PN Y8
J 2
(-2810 2185);
DISPLAY 0.680851 (-2810 2185);
PAINT MONO (-2810 2185);
FORCEPROP 0 LASTPIN (-2800 2775) $PN Y73
J 2
(-2810 2785);
DISPLAY 0.680851 (-2810 2785);
PAINT MONO (-2810 2785);
FORCEPROP 2 LAST CDS_LIB pure_quanta
J 0
(-1600 1850);
DISPLAY INVISIBLE (-1600 1850);
FORCEPROP 1 LAST NEEDS_NO_SIZE TRUE
J 0
(-1600 1850);
DISPLAY 0.723404 (-1600 1850);
PAINT GREEN (-1600 1850);
DISPLAY INVISIBLE (-1600 1850);
FORCEPROP 1 LAST CDS_LMAN_SYM_OUTLINE -1050,2150,1050,-2100
J 0
(-1600 1850);
DISPLAY 0.468085 (-1600 1850);
PAINT GREEN (-1600 1850);
DISPLAY INVISIBLE (-1600 1850);
FORCEPROP 0 LAST CDS_LOCATION U1
J 0
(-2650 4325);
DISPLAY 1.021277 (-2650 4325);
DISPLAY INVISIBLE (-2650 4325);
FORCEPROP 0 LAST $SEC 40
J 0
(-2650 4325);
DISPLAY 0.680851 (-2650 4325);
PAINT MONO (-2650 4325);
DISPLAY INVISIBLE (-2650 4325);
FORCEPROP 2 LAST CDS_SEC 40
J 0
(-2650 4325);
DISPLAY 1.021277 (-2650 4325);
DISPLAY INVISIBLE (-2650 4325);
FORCEPROP 1 LAST PATH I2
J 0
(-1600 1850);
DISPLAY 0.723404 (-1600 1850);
PAINT GREEN (-1600 1850);
DISPLAY INVISIBLE (-1600 1850);
FORCEADD UNIVERSAL_GND..1
(-150 -675);
FORCEPROP 3 LASTPIN (-150 -625) SIG_NAME GND\g
J 0
(-140 -615);
DISPLAY 0.659574 (-140 -615);
PAINT MONO (-140 -615);
DISPLAY INVISIBLE (-140 -615);
FORCEPROP 2 LAST CDS_LIB logical_power
J 0
(-150 -675);
PAINT MONO (-150 -675);
DISPLAY INVISIBLE (-150 -675);
FORCEPROP 1 LAST HDL_POWER GND
J 1
(-125 -750);
DISPLAY 0.872340 (-125 -750);
PAINT GREEN (-125 -750);
DISPLAY INVISIBLE (-125 -750);
FORCEPROP 1 LAST PATH I3
J 0
(-75 -675);
DISPLAY 0.872340 (-75 -675);
PAINT AQUA (-75 -675);
DISPLAY INVISIBLE (-75 -675);
FORCEADD UNIVERSAL_GND..1
(0 -675);
FORCEPROP 3 LASTPIN (0 -625) SIG_NAME GND\g
J 0
(10 -615);
DISPLAY 0.659574 (10 -615);
PAINT MONO (10 -615);
DISPLAY INVISIBLE (10 -615);
FORCEPROP 2 LAST CDS_LIB logical_power
J 0
(0 -675);
PAINT MONO (0 -675);
DISPLAY INVISIBLE (0 -675);
FORCEPROP 1 LAST HDL_POWER GND
J 1
(25 -750);
DISPLAY 0.872340 (25 -750);
PAINT GREEN (25 -750);
DISPLAY INVISIBLE (25 -750);
FORCEPROP 1 LAST PATH I4
J 0
(75 -675);
DISPLAY 0.872340 (75 -675);
PAINT AQUA (75 -675);
DISPLAY INVISIBLE (75 -675);
FORCEADD SOCKET4677_AZIF0045P001C01CS..41
(1450 1850);
FORCEPROP 1 LAST PART_NUMBER DGA^7000023
J 0
(400 4100);
DISPLAY 0.723404 (400 4100);
PAINT GREEN (400 4100);
DISPLAY INVISIBLE (400 4100);
FORCEPROP 2 LAST PART_TYPE SMLF
J 0
(400 4275);
DISPLAY 1.021277 (400 4275);
FORCEPROP 2 LAST VALUE SOCKET4677_AZIF0045-P001C01CS
J 0
(400 4225);
DISPLAY 1.021277 (400 4225);
FORCEPROP 1 LAST MATERIAL IO
J 0
(400 4025);
DISPLAY 0.723404 (400 4025);
PAINT GREEN (400 4025);
FORCEPROP 1 LAST $LOCATION U1
J 0
(400 4175);
DISPLAY 0.723404 (400 4175);
PAINT GREEN (400 4175);
FORCEPROP 0 LASTPIN (2650 75) $PN E52
J 0
(2660 85);
DISPLAY 0.680851 (2660 85);
PAINT MONO (2660 85);
FORCEPROP 0 LASTPIN (2650 125) $PN E74
J 0
(2660 135);
DISPLAY 0.680851 (2660 135);
PAINT MONO (2660 135);
FORCEPROP 0 LASTPIN (2650 225) $PN E78
J 0
(2660 235);
DISPLAY 0.680851 (2660 235);
PAINT MONO (2660 235);
FORCEPROP 0 LASTPIN (2650 175) $PN E76
J 0
(2660 185);
DISPLAY 0.680851 (2660 185);
PAINT MONO (2660 185);
FORCEPROP 0 LASTPIN (2650 275) $PN E86
J 0
(2660 285);
DISPLAY 0.680851 (2660 285);
PAINT MONO (2660 285);
FORCEPROP 0 LASTPIN (2650 425) $PN F12
J 0
(2660 435);
DISPLAY 0.680851 (2660 435);
PAINT MONO (2660 435);
FORCEPROP 0 LASTPIN (2650 475) $PN F18
J 0
(2660 485);
DISPLAY 0.680851 (2660 485);
PAINT MONO (2660 485);
FORCEPROP 0 LASTPIN (2650 675) $PN F42
J 0
(2660 685);
DISPLAY 0.680851 (2660 685);
PAINT MONO (2660 685);
FORCEPROP 0 LASTPIN (2650 775) $PN F55
J 0
(2660 785);
DISPLAY 0.680851 (2660 785);
PAINT MONO (2660 785);
FORCEPROP 0 LASTPIN (2650 375) $PN F6
J 0
(2660 385);
DISPLAY 0.680851 (2660 385);
PAINT MONO (2660 385);
FORCEPROP 0 LASTPIN (2650 825) $PN F61
J 0
(2660 835);
DISPLAY 0.680851 (2660 835);
PAINT MONO (2660 835);
FORCEPROP 0 LASTPIN (2650 875) $PN F67
J 0
(2660 885);
DISPLAY 0.680851 (2660 885);
PAINT MONO (2660 885);
FORCEPROP 0 LASTPIN (2650 925) $PN F73
J 0
(2660 935);
DISPLAY 0.680851 (2660 935);
PAINT MONO (2660 935);
FORCEPROP 0 LASTPIN (2650 975) $PN F79
J 0
(2660 985);
DISPLAY 0.680851 (2660 985);
PAINT MONO (2660 985);
FORCEPROP 0 LASTPIN (2650 1225) $PN G11
J 0
(2660 1235);
DISPLAY 0.680851 (2660 1235);
PAINT MONO (2660 1235);
FORCEPROP 0 LASTPIN (2650 1325) $PN G17
J 0
(2660 1335);
DISPLAY 0.680851 (2660 1335);
PAINT MONO (2660 1335);
FORCEPROP 0 LASTPIN (2650 1475) $PN G25
J 0
(2660 1485);
DISPLAY 0.680851 (2660 1485);
PAINT MONO (2660 1485);
FORCEPROP 0 LASTPIN (2650 1125) $PN G3
J 0
(2660 1135);
DISPLAY 0.680851 (2660 1135);
PAINT MONO (2660 1135);
FORCEPROP 0 LASTPIN (2650 1625) $PN G35
J 0
(2660 1635);
DISPLAY 0.680851 (2660 1635);
PAINT MONO (2660 1635);
FORCEPROP 0 LASTPIN (2650 1825) $PN G48
J 0
(2660 1835);
DISPLAY 0.680851 (2660 1835);
PAINT MONO (2660 1835);
FORCEPROP 0 LASTPIN (2650 2025) $PN G60
J 0
(2660 2035);
DISPLAY 0.680851 (2660 2035);
PAINT MONO (2660 2035);
FORCEPROP 0 LASTPIN (2650 2125) $PN G66
J 0
(2660 2135);
DISPLAY 0.680851 (2660 2135);
PAINT MONO (2660 2135);
FORCEPROP 0 LASTPIN (2650 2175) $PN G68
J 0
(2660 2185);
DISPLAY 0.680851 (2660 2185);
PAINT MONO (2660 2185);
FORCEPROP 0 LASTPIN (2650 1175) $PN G7
J 0
(2660 1185);
DISPLAY 0.680851 (2660 1185);
PAINT MONO (2660 1185);
FORCEPROP 0 LASTPIN (2650 2275) $PN G74
J 0
(2660 2285);
DISPLAY 0.680851 (2660 2285);
PAINT MONO (2660 2285);
FORCEPROP 0 LASTPIN (2650 2725) $PN H14
J 0
(2660 2735);
DISPLAY 0.680851 (2660 2735);
PAINT MONO (2660 2735);
FORCEPROP 0 LASTPIN (2650 2475) $PN H2
J 0
(2660 2485);
DISPLAY 0.680851 (2660 2485);
PAINT MONO (2660 2485);
FORCEPROP 0 LASTPIN (2650 3325) $PN H51
J 0
(2660 3335);
DISPLAY 0.680851 (2660 3335);
PAINT MONO (2660 3335);
FORCEPROP 0 LASTPIN (2650 3425) $PN H57
J 0
(2660 3435);
DISPLAY 0.680851 (2660 3435);
PAINT MONO (2660 3435);
FORCEPROP 0 LASTPIN (2650 3575) $PN H65
J 0
(2660 3585);
DISPLAY 0.680851 (2660 3585);
PAINT MONO (2660 3585);
FORCEPROP 0 LASTPIN (2650 3725) $PN H75
J 0
(2660 3735);
DISPLAY 0.680851 (2660 3735);
PAINT MONO (2660 3735);
FORCEPROP 0 LASTPIN (2650 525) $PN F24
J 0
(2660 535);
DISPLAY 0.680851 (2660 535);
PAINT MONO (2660 535);
FORCEPROP 0 LASTPIN (2650 575) $PN F30
J 0
(2660 585);
DISPLAY 0.680851 (2660 585);
PAINT MONO (2660 585);
FORCEPROP 0 LASTPIN (2650 625) $PN F36
J 0
(2660 635);
DISPLAY 0.680851 (2660 635);
PAINT MONO (2660 635);
FORCEPROP 0 LASTPIN (2650 325) $PN F4
J 0
(2660 335);
DISPLAY 0.680851 (2660 335);
PAINT MONO (2660 335);
FORCEPROP 0 LASTPIN (2650 725) $PN F49
J 0
(2660 735);
DISPLAY 0.680851 (2660 735);
PAINT MONO (2660 735);
FORCEPROP 0 LASTPIN (250 25) $PN J21
J 2
(240 35);
DISPLAY 0.680851 (240 35);
PAINT MONO (240 35);
FORCEPROP 0 LASTPIN (2650 1025) $PN F83
J 0
(2660 1035);
DISPLAY 0.680851 (2660 1035);
PAINT MONO (2660 1035);
FORCEPROP 0 LASTPIN (2650 1075) $PN F89
J 0
(2660 1085);
DISPLAY 0.680851 (2660 1085);
PAINT MONO (2660 1085);
FORCEPROP 0 LASTPIN (2650 1275) $PN G13
J 0
(2660 1285);
DISPLAY 0.680851 (2660 1285);
PAINT MONO (2660 1285);
FORCEPROP 0 LASTPIN (2650 1375) $PN G19
J 0
(2660 1385);
DISPLAY 0.680851 (2660 1385);
PAINT MONO (2660 1385);
FORCEPROP 0 LASTPIN (250 175) $PN J39
J 2
(240 185);
DISPLAY 0.680851 (240 185);
PAINT MONO (240 185);
FORCEPROP 0 LASTPIN (2650 1425) $PN G23
J 0
(2660 1435);
DISPLAY 0.680851 (2660 1435);
PAINT MONO (2660 1435);
FORCEPROP 0 LASTPIN (250 -125) $PN J5
J 2
(240 -115);
DISPLAY 0.680851 (240 -115);
PAINT MONO (240 -115);
FORCEPROP 0 LASTPIN (2650 1525) $PN G29
J 0
(2660 1535);
DISPLAY 0.680851 (2660 1535);
PAINT MONO (2660 1535);
FORCEPROP 0 LASTPIN (2650 1575) $PN G31
J 0
(2660 1585);
DISPLAY 0.680851 (2660 1585);
PAINT MONO (2660 1585);
FORCEPROP 0 LASTPIN (2650 1675) $PN G37
J 0
(2660 1685);
DISPLAY 0.680851 (2660 1685);
PAINT MONO (2660 1685);
FORCEPROP 0 LASTPIN (2650 1725) $PN G41
J 0
(2660 1735);
DISPLAY 0.680851 (2660 1735);
PAINT MONO (2660 1735);
FORCEPROP 0 LASTPIN (250 375) $PN J64
J 2
(240 385);
DISPLAY 0.680851 (240 385);
PAINT MONO (240 385);
FORCEPROP 0 LASTPIN (2650 1775) $PN G43
J 0
(2660 1785);
DISPLAY 0.680851 (2660 1785);
PAINT MONO (2660 1785);
FORCEPROP 0 LASTPIN (250 425) $PN J70
J 2
(240 435);
DISPLAY 0.680851 (240 435);
PAINT MONO (240 435);
FORCEPROP 0 LASTPIN (2650 1875) $PN G50
J 0
(2660 1885);
DISPLAY 0.680851 (2660 1885);
PAINT MONO (2660 1885);
FORCEPROP 0 LASTPIN (2650 1925) $PN G54
J 0
(2660 1935);
DISPLAY 0.680851 (2660 1935);
PAINT MONO (2660 1935);
FORCEPROP 0 LASTPIN (2650 1975) $PN G56
J 0
(2660 1985);
DISPLAY 0.680851 (2660 1985);
PAINT MONO (2660 1985);
FORCEPROP 0 LASTPIN (2650 2075) $PN G62
J 0
(2660 2085);
DISPLAY 0.680851 (2660 2085);
PAINT MONO (2660 2085);
FORCEPROP 0 LASTPIN (2650 2225) $PN G72
J 0
(2660 2235);
DISPLAY 0.680851 (2660 2235);
PAINT MONO (2660 2235);
FORCEPROP 0 LASTPIN (250 675) $PN J88
J 2
(240 685);
DISPLAY 0.680851 (240 685);
PAINT MONO (240 685);
FORCEPROP 0 LASTPIN (250 -75) $PN J9
J 2
(240 -65);
DISPLAY 0.680851 (240 -65);
PAINT MONO (240 -65);
FORCEPROP 0 LASTPIN (250 825) $PN K12
J 2
(240 835);
DISPLAY 0.680851 (240 835);
PAINT MONO (240 835);
FORCEPROP 0 LASTPIN (250 875) $PN K14
J 2
(240 885);
DISPLAY 0.680851 (240 885);
PAINT MONO (240 885);
FORCEPROP 0 LASTPIN (250 725) $PN K2
J 2
(240 735);
DISPLAY 0.680851 (240 735);
PAINT MONO (240 735);
FORCEPROP 0 LASTPIN (2650 2325) $PN G84
J 0
(2660 2335);
DISPLAY 0.680851 (2660 2335);
PAINT MONO (2660 2335);
FORCEPROP 0 LASTPIN (2650 2375) $PN G88
J 0
(2660 2385);
DISPLAY 0.680851 (2660 2385);
PAINT MONO (2660 2385);
FORCEPROP 0 LASTPIN (250 925) $PN K42
J 2
(240 935);
DISPLAY 0.680851 (240 935);
PAINT MONO (240 935);
FORCEPROP 0 LASTPIN (250 975) $PN K49
J 2
(240 985);
DISPLAY 0.680851 (240 985);
PAINT MONO (240 985);
FORCEPROP 0 LASTPIN (2650 2425) $PN G90
J 0
(2660 2435);
DISPLAY 0.680851 (2660 2435);
PAINT MONO (2660 2435);
FORCEPROP 0 LASTPIN (2650 2675) $PN H10
J 0
(2660 2685);
DISPLAY 0.680851 (2660 2685);
PAINT MONO (2660 2685);
FORCEPROP 0 LASTPIN (2650 2775) $PN H16
J 0
(2660 2785);
DISPLAY 0.680851 (2660 2785);
PAINT MONO (2660 2785);
FORCEPROP 0 LASTPIN (2650 2825) $PN H20
J 0
(2660 2835);
DISPLAY 0.680851 (2660 2835);
PAINT MONO (2660 2835);
FORCEPROP 0 LASTPIN (2650 2875) $PN H22
J 0
(2660 2885);
DISPLAY 0.680851 (2660 2885);
PAINT MONO (2660 2885);
FORCEPROP 0 LASTPIN (2650 2925) $PN H26
J 0
(2660 2935);
DISPLAY 0.680851 (2660 2935);
PAINT MONO (2660 2935);
FORCEPROP 0 LASTPIN (2650 2975) $PN H28
J 0
(2660 2985);
DISPLAY 0.680851 (2660 2985);
PAINT MONO (2660 2985);
FORCEPROP 0 LASTPIN (2650 3025) $PN H32
J 0
(2660 3035);
DISPLAY 0.680851 (2660 3035);
PAINT MONO (2660 3035);
FORCEPROP 0 LASTPIN (2650 3075) $PN H34
J 0
(2660 3085);
DISPLAY 0.680851 (2660 3085);
PAINT MONO (2660 3085);
FORCEPROP 0 LASTPIN (2650 3125) $PN H38
J 0
(2660 3135);
DISPLAY 0.680851 (2660 3135);
PAINT MONO (2660 3135);
FORCEPROP 0 LASTPIN (250 1425) $PN L19
J 2
(240 1435);
DISPLAY 0.680851 (240 1435);
PAINT MONO (240 1435);
FORCEPROP 0 LASTPIN (2650 2525) $PN H4
J 0
(2660 2535);
DISPLAY 0.680851 (2660 2535);
PAINT MONO (2660 2535);
FORCEPROP 0 LASTPIN (2650 3175) $PN H40
J 0
(2660 3185);
DISPLAY 0.680851 (2660 3185);
PAINT MONO (2660 3185);
FORCEPROP 0 LASTPIN (2650 3225) $PN H44
J 0
(2660 3235);
DISPLAY 0.680851 (2660 3235);
PAINT MONO (2660 3235);
FORCEPROP 0 LASTPIN (2650 3275) $PN H47
J 0
(2660 3285);
DISPLAY 0.680851 (2660 3285);
PAINT MONO (2660 3285);
FORCEPROP 0 LASTPIN (2650 3375) $PN H53
J 0
(2660 3385);
DISPLAY 0.680851 (2660 3385);
PAINT MONO (2660 3385);
FORCEPROP 0 LASTPIN (2650 3475) $PN H59
J 0
(2660 3485);
DISPLAY 0.680851 (2660 3485);
PAINT MONO (2660 3485);
FORCEPROP 0 LASTPIN (2650 2575) $PN H6
J 0
(2660 2585);
DISPLAY 0.680851 (2660 2585);
PAINT MONO (2660 2585);
FORCEPROP 0 LASTPIN (2650 3525) $PN H63
J 0
(2660 3535);
DISPLAY 0.680851 (2660 3535);
PAINT MONO (2660 3535);
FORCEPROP 0 LASTPIN (2650 3625) $PN H69
J 0
(2660 3635);
DISPLAY 0.680851 (2660 3635);
PAINT MONO (2660 3635);
FORCEPROP 0 LASTPIN (2650 3675) $PN H71
J 0
(2660 3685);
DISPLAY 0.680851 (2660 3685);
PAINT MONO (2660 3685);
FORCEPROP 0 LASTPIN (2650 3775) $PN H79
J 0
(2660 3785);
DISPLAY 0.680851 (2660 3785);
PAINT MONO (2660 3785);
FORCEPROP 0 LASTPIN (2650 2625) $PN H8
J 0
(2660 2635);
DISPLAY 0.680851 (2660 2635);
PAINT MONO (2660 2635);
FORCEPROP 0 LASTPIN (2650 3825) $PN H81
J 0
(2660 3835);
DISPLAY 0.680851 (2660 3835);
PAINT MONO (2660 3835);
FORCEPROP 0 LASTPIN (250 -25) $PN J15
J 2
(240 -15);
DISPLAY 0.680851 (240 -15);
PAINT MONO (240 -15);
FORCEPROP 0 LASTPIN (250 75) $PN J27
J 2
(240 85);
DISPLAY 0.680851 (240 85);
PAINT MONO (240 85);
FORCEPROP 0 LASTPIN (250 125) $PN J33
J 2
(240 135);
DISPLAY 0.680851 (240 135);
PAINT MONO (240 135);
FORCEPROP 0 LASTPIN (250 225) $PN J45
J 2
(240 235);
DISPLAY 0.680851 (240 235);
PAINT MONO (240 235);
FORCEPROP 0 LASTPIN (250 275) $PN J52
J 2
(240 285);
DISPLAY 0.680851 (240 285);
PAINT MONO (240 285);
FORCEPROP 0 LASTPIN (250 325) $PN J58
J 2
(240 335);
DISPLAY 0.680851 (240 335);
PAINT MONO (240 335);
FORCEPROP 0 LASTPIN (250 2375) $PN L58
J 2
(240 2385);
DISPLAY 0.680851 (240 2385);
PAINT MONO (240 2385);
FORCEPROP 0 LASTPIN (250 475) $PN J76
J 2
(240 485);
DISPLAY 0.680851 (240 485);
PAINT MONO (240 485);
FORCEPROP 0 LASTPIN (250 525) $PN J78
J 2
(240 535);
DISPLAY 0.680851 (240 535);
PAINT MONO (240 535);
FORCEPROP 0 LASTPIN (250 575) $PN J84
J 2
(240 585);
DISPLAY 0.680851 (240 585);
PAINT MONO (240 585);
FORCEPROP 0 LASTPIN (250 625) $PN J86
J 2
(240 635);
DISPLAY 0.680851 (240 635);
PAINT MONO (240 635);
FORCEPROP 0 LASTPIN (250 1025) $PN K77
J 2
(240 1035);
DISPLAY 0.680851 (240 1035);
PAINT MONO (240 1035);
FORCEPROP 0 LASTPIN (250 2675) $PN L70
J 2
(240 2685);
DISPLAY 0.680851 (240 2685);
PAINT MONO (240 2685);
FORCEPROP 0 LASTPIN (250 775) $PN K8
J 2
(240 785);
DISPLAY 0.680851 (240 785);
PAINT MONO (240 785);
FORCEPROP 0 LASTPIN (250 1075) $PN K83
J 2
(240 1085);
DISPLAY 0.680851 (240 1085);
PAINT MONO (240 1085);
FORCEPROP 0 LASTPIN (250 1125) $PN K85
J 2
(240 1135);
DISPLAY 0.680851 (240 1135);
PAINT MONO (240 1135);
FORCEPROP 0 LASTPIN (250 1275) $PN L13
J 2
(240 1285);
DISPLAY 0.680851 (240 1285);
PAINT MONO (240 1285);
FORCEPROP 0 LASTPIN (250 1325) $PN L15
J 2
(240 1335);
DISPLAY 0.680851 (240 1335);
PAINT MONO (240 1335);
FORCEPROP 0 LASTPIN (250 2925) $PN L88
J 2
(240 2935);
DISPLAY 0.680851 (240 2935);
PAINT MONO (240 2935);
FORCEPROP 0 LASTPIN (250 1225) $PN L9
J 2
(240 1235);
DISPLAY 0.680851 (240 1235);
PAINT MONO (240 1235);
FORCEPROP 0 LASTPIN (250 2975) $PN L90
J 2
(240 2985);
DISPLAY 0.680851 (240 2985);
PAINT MONO (240 2985);
FORCEPROP 0 LASTPIN (250 3125) $PN M12
J 2
(240 3135);
DISPLAY 0.680851 (240 3135);
PAINT MONO (240 3135);
FORCEPROP 0 LASTPIN (250 1375) $PN L17
J 2
(240 1385);
DISPLAY 0.680851 (240 1385);
PAINT MONO (240 1385);
FORCEPROP 0 LASTPIN (250 1475) $PN L21
J 2
(240 1485);
DISPLAY 0.680851 (240 1485);
PAINT MONO (240 1485);
FORCEPROP 0 LASTPIN (250 3025) $PN M4
J 2
(240 3035);
DISPLAY 0.680851 (240 3035);
PAINT MONO (240 3035);
FORCEPROP 0 LASTPIN (250 3175) $PN M42
J 2
(240 3185);
DISPLAY 0.680851 (240 3185);
PAINT MONO (240 3185);
FORCEPROP 0 LASTPIN (250 3225) $PN M49
J 2
(240 3235);
DISPLAY 0.680851 (240 3235);
PAINT MONO (240 3235);
FORCEPROP 0 LASTPIN (250 1525) $PN L23
J 2
(240 1535);
DISPLAY 0.680851 (240 1535);
PAINT MONO (240 1535);
FORCEPROP 0 LASTPIN (250 1575) $PN L25
J 2
(240 1585);
DISPLAY 0.680851 (240 1585);
PAINT MONO (240 1585);
FORCEPROP 0 LASTPIN (250 3075) $PN M8
J 2
(240 3085);
DISPLAY 0.680851 (240 3085);
PAINT MONO (240 3085);
FORCEPROP 0 LASTPIN (250 1625) $PN L27
J 2
(240 1635);
DISPLAY 0.680851 (240 1635);
PAINT MONO (240 1635);
FORCEPROP 0 LASTPIN (250 1675) $PN L29
J 2
(240 1685);
DISPLAY 0.680851 (240 1685);
PAINT MONO (240 1685);
FORCEPROP 0 LASTPIN (250 1725) $PN L31
J 2
(240 1735);
DISPLAY 0.680851 (240 1735);
PAINT MONO (240 1735);
FORCEPROP 0 LASTPIN (250 1775) $PN L33
J 2
(240 1785);
DISPLAY 0.680851 (240 1785);
PAINT MONO (240 1785);
FORCEPROP 0 LASTPIN (250 1825) $PN L35
J 2
(240 1835);
DISPLAY 0.680851 (240 1835);
PAINT MONO (240 1835);
FORCEPROP 0 LASTPIN (250 1875) $PN L37
J 2
(240 1885);
DISPLAY 0.680851 (240 1885);
PAINT MONO (240 1885);
FORCEPROP 0 LASTPIN (250 3425) $PN N21
J 2
(240 3435);
DISPLAY 0.680851 (240 3435);
PAINT MONO (240 3435);
FORCEPROP 0 LASTPIN (250 1925) $PN L39
J 2
(240 1935);
DISPLAY 0.680851 (240 1935);
PAINT MONO (240 1935);
FORCEPROP 0 LASTPIN (250 1975) $PN L41
J 2
(240 1985);
DISPLAY 0.680851 (240 1985);
PAINT MONO (240 1985);
FORCEPROP 0 LASTPIN (250 2025) $PN L43
J 2
(240 2035);
DISPLAY 0.680851 (240 2035);
PAINT MONO (240 2035);
FORCEPROP 0 LASTPIN (250 2075) $PN L45
J 2
(240 2085);
DISPLAY 0.680851 (240 2085);
PAINT MONO (240 2085);
FORCEPROP 0 LASTPIN (250 3575) $PN N39
J 2
(240 3585);
DISPLAY 0.680851 (240 3585);
PAINT MONO (240 3585);
FORCEPROP 0 LASTPIN (250 2125) $PN L48
J 2
(240 2135);
DISPLAY 0.680851 (240 2135);
PAINT MONO (240 2135);
FORCEPROP 0 LASTPIN (250 1175) $PN L5
J 2
(240 1185);
DISPLAY 0.680851 (240 1185);
PAINT MONO (240 1185);
FORCEPROP 0 LASTPIN (250 2175) $PN L50
J 2
(240 2185);
DISPLAY 0.680851 (240 2185);
PAINT MONO (240 2185);
FORCEPROP 0 LASTPIN (250 2225) $PN L52
J 2
(240 2235);
DISPLAY 0.680851 (240 2235);
PAINT MONO (240 2235);
FORCEPROP 0 LASTPIN (250 2275) $PN L54
J 2
(240 2285);
DISPLAY 0.680851 (240 2285);
PAINT MONO (240 2285);
FORCEPROP 0 LASTPIN (250 3775) $PN N64
J 2
(240 3785);
DISPLAY 0.680851 (240 3785);
PAINT MONO (240 3785);
FORCEPROP 0 LASTPIN (250 2325) $PN L56
J 2
(240 2335);
DISPLAY 0.680851 (240 2335);
PAINT MONO (240 2335);
FORCEPROP 0 LASTPIN (250 2425) $PN L60
J 2
(240 2435);
DISPLAY 0.680851 (240 2435);
PAINT MONO (240 2435);
FORCEPROP 0 LASTPIN (250 2475) $PN L62
J 2
(240 2485);
DISPLAY 0.680851 (240 2485);
PAINT MONO (240 2485);
FORCEPROP 0 LASTPIN (250 2525) $PN L64
J 2
(240 2535);
DISPLAY 0.680851 (240 2535);
PAINT MONO (240 2535);
FORCEPROP 0 LASTPIN (250 2575) $PN L66
J 2
(240 2585);
DISPLAY 0.680851 (240 2585);
PAINT MONO (240 2585);
FORCEPROP 0 LASTPIN (250 2625) $PN L68
J 2
(240 2635);
DISPLAY 0.680851 (240 2635);
PAINT MONO (240 2635);
FORCEPROP 0 LASTPIN (250 2725) $PN L72
J 2
(240 2735);
DISPLAY 0.680851 (240 2735);
PAINT MONO (240 2735);
FORCEPROP 0 LASTPIN (250 2775) $PN L74
J 2
(240 2785);
DISPLAY 0.680851 (240 2785);
PAINT MONO (240 2785);
FORCEPROP 0 LASTPIN (250 2825) $PN L76
J 2
(240 2835);
DISPLAY 0.680851 (240 2835);
PAINT MONO (240 2835);
FORCEPROP 0 LASTPIN (250 2875) $PN L78
J 2
(240 2885);
DISPLAY 0.680851 (240 2885);
PAINT MONO (240 2885);
FORCEPROP 0 LASTPIN (250 3275) $PN M81
J 2
(240 3285);
DISPLAY 0.680851 (240 3285);
PAINT MONO (240 3285);
FORCEPROP 0 LASTPIN (250 3325) $PN M83
J 2
(240 3335);
DISPLAY 0.680851 (240 3335);
PAINT MONO (240 3335);
FORCEPROP 0 LASTPIN (250 3375) $PN N15
J 2
(240 3385);
DISPLAY 0.680851 (240 3385);
PAINT MONO (240 3385);
FORCEPROP 0 LASTPIN (250 3475) $PN N27
J 2
(240 3485);
DISPLAY 0.680851 (240 3485);
PAINT MONO (240 3485);
FORCEPROP 0 LASTPIN (250 3525) $PN N33
J 2
(240 3535);
DISPLAY 0.680851 (240 3535);
PAINT MONO (240 3535);
FORCEPROP 0 LASTPIN (250 3625) $PN N45
J 2
(240 3635);
DISPLAY 0.680851 (240 3635);
PAINT MONO (240 3635);
FORCEPROP 0 LASTPIN (250 3675) $PN N52
J 2
(240 3685);
DISPLAY 0.680851 (240 3685);
PAINT MONO (240 3685);
FORCEPROP 0 LASTPIN (250 3725) $PN N58
J 2
(240 3735);
DISPLAY 0.680851 (240 3735);
PAINT MONO (240 3735);
FORCEPROP 0 LASTPIN (250 3825) $PN N70
J 2
(240 3835);
DISPLAY 0.680851 (240 3835);
PAINT MONO (240 3835);
FORCEPROP 2 LAST CDS_LIB pure_quanta
J 0
(1450 1850);
DISPLAY INVISIBLE (1450 1850);
FORCEPROP 1 LAST NEEDS_NO_SIZE TRUE
J 0
(1450 1850);
DISPLAY 0.723404 (1450 1850);
PAINT GREEN (1450 1850);
DISPLAY INVISIBLE (1450 1850);
FORCEPROP 1 LAST CDS_LMAN_SYM_OUTLINE -1050,2150,1050,-2100
J 0
(1450 1850);
DISPLAY 0.468085 (1450 1850);
PAINT GREEN (1450 1850);
DISPLAY INVISIBLE (1450 1850);
FORCEPROP 0 LAST CDS_LOCATION U1
J 0
(400 4325);
DISPLAY 1.021277 (400 4325);
DISPLAY INVISIBLE (400 4325);
FORCEPROP 0 LAST $SEC 41
J 0
(400 4325);
DISPLAY 0.680851 (400 4325);
PAINT MONO (400 4325);
DISPLAY INVISIBLE (400 4325);
FORCEPROP 2 LAST CDS_SEC 41
J 0
(400 4325);
DISPLAY 1.021277 (400 4325);
DISPLAY INVISIBLE (400 4325);
FORCEPROP 1 LAST PATH I5
J 0
(1450 1850);
DISPLAY 0.723404 (1450 1850);
PAINT GREEN (1450 1850);
DISPLAY INVISIBLE (1450 1850);
FORCEADD UNIVERSAL_GND..1
(2900 -675);
FORCEPROP 3 LASTPIN (2900 -625) SIG_NAME GND\g
J 0
(2910 -615);
DISPLAY 0.659574 (2910 -615);
PAINT MONO (2910 -615);
DISPLAY INVISIBLE (2910 -615);
FORCEPROP 2 LAST CDS_LIB logical_power
J 0
(2900 -675);
PAINT MONO (2900 -675);
DISPLAY INVISIBLE (2900 -675);
FORCEPROP 1 LAST HDL_POWER GND
J 1
(2925 -750);
DISPLAY 0.872340 (2925 -750);
PAINT GREEN (2925 -750);
DISPLAY INVISIBLE (2925 -750);
FORCEPROP 1 LAST PATH I6
J 0
(2975 -675);
DISPLAY 0.872340 (2975 -675);
PAINT AQUA (2975 -675);
DISPLAY INVISIBLE (2975 -675);
FORCEADD UNIVERSAL_GND..1
(3025 -675);
FORCEPROP 3 LASTPIN (3025 -625) SIG_NAME GND\g
J 0
(3035 -615);
DISPLAY 0.659574 (3035 -615);
PAINT MONO (3035 -615);
DISPLAY INVISIBLE (3035 -615);
FORCEPROP 2 LAST CDS_LIB logical_power
J 0
(3025 -675);
PAINT MONO (3025 -675);
DISPLAY INVISIBLE (3025 -675);
FORCEPROP 1 LAST HDL_POWER GND
J 1
(3050 -750);
DISPLAY 0.872340 (3050 -750);
PAINT GREEN (3050 -750);
DISPLAY INVISIBLE (3050 -750);
FORCEPROP 1 LAST PATH I7
J 0
(3100 -675);
DISPLAY 0.872340 (3100 -675);
PAINT AQUA (3100 -675);
DISPLAY INVISIBLE (3100 -675);
FORCEADD SOCKET4677_AZIF0045P001C01CS..42
(4475 1900);
FORCEPROP 1 LAST PART_NUMBER DGA^7000023
J 0
(3425 4100);
DISPLAY 0.723404 (3425 4100);
PAINT GREEN (3425 4100);
DISPLAY INVISIBLE (3425 4100);
FORCEPROP 2 LAST PART_TYPE SMLF
J 0
(3425 4275);
DISPLAY 1.021277 (3425 4275);
FORCEPROP 1 LAST MATERIAL IO
J 0
(3425 4025);
DISPLAY 0.723404 (3425 4025);
PAINT GREEN (3425 4025);
FORCEPROP 2 LAST VALUE SOCKET4677_AZIF0045-P001C01CS
J 0
(3425 4225);
DISPLAY 1.021277 (3425 4225);
FORCEPROP 1 LAST $LOCATION U1
J 0
(3425 4175);
DISPLAY 0.723404 (3425 4175);
PAINT GREEN (3425 4175);
FORCEPROP 0 LASTPIN (3275 -25) $PN A11
J 2
(3265 -15);
DISPLAY 0.680851 (3265 -15);
PAINT MONO (3265 -15);
FORCEPROP 0 LASTPIN (3275 25) $PN A13
J 2
(3265 35);
DISPLAY 0.680851 (3265 35);
PAINT MONO (3265 35);
FORCEPROP 0 LASTPIN (3275 75) $PN A17
J 2
(3265 85);
DISPLAY 0.680851 (3265 85);
PAINT MONO (3265 85);
FORCEPROP 0 LASTPIN (3275 125) $PN A19
J 2
(3265 135);
DISPLAY 0.680851 (3265 135);
PAINT MONO (3265 135);
FORCEPROP 0 LASTPIN (3275 175) $PN A23
J 2
(3265 185);
DISPLAY 0.680851 (3265 185);
PAINT MONO (3265 185);
FORCEPROP 0 LASTPIN (3275 225) $PN A25
J 2
(3265 235);
DISPLAY 0.680851 (3265 235);
PAINT MONO (3265 235);
FORCEPROP 0 LASTPIN (3275 275) $PN A29
J 2
(3265 285);
DISPLAY 0.680851 (3265 285);
PAINT MONO (3265 285);
FORCEPROP 0 LASTPIN (3275 325) $PN A31
J 2
(3265 335);
DISPLAY 0.680851 (3265 335);
PAINT MONO (3265 335);
FORCEPROP 0 LASTPIN (3275 375) $PN A35
J 2
(3265 385);
DISPLAY 0.680851 (3265 385);
PAINT MONO (3265 385);
FORCEPROP 0 LASTPIN (3275 425) $PN A37
J 2
(3265 435);
DISPLAY 0.680851 (3265 435);
PAINT MONO (3265 435);
FORCEPROP 0 LASTPIN (3275 475) $PN A41
J 2
(3265 485);
DISPLAY 0.680851 (3265 485);
PAINT MONO (3265 485);
FORCEPROP 0 LASTPIN (3275 525) $PN A50
J 2
(3265 535);
DISPLAY 0.680851 (3265 535);
PAINT MONO (3265 535);
FORCEPROP 0 LASTPIN (3275 575) $PN A54
J 2
(3265 585);
DISPLAY 0.680851 (3265 585);
PAINT MONO (3265 585);
FORCEPROP 0 LASTPIN (3275 625) $PN A56
J 2
(3265 635);
DISPLAY 0.680851 (3265 635);
PAINT MONO (3265 635);
FORCEPROP 0 LASTPIN (3275 675) $PN A60
J 2
(3265 685);
DISPLAY 0.680851 (3265 685);
PAINT MONO (3265 685);
FORCEPROP 0 LASTPIN (3275 725) $PN A62
J 2
(3265 735);
DISPLAY 0.680851 (3265 735);
PAINT MONO (3265 735);
FORCEPROP 0 LASTPIN (3275 825) $PN B12
J 2
(3265 835);
DISPLAY 0.680851 (3265 835);
PAINT MONO (3265 835);
FORCEPROP 0 LASTPIN (3275 875) $PN B18
J 2
(3265 885);
DISPLAY 0.680851 (3265 885);
PAINT MONO (3265 885);
FORCEPROP 0 LASTPIN (3275 925) $PN B24
J 2
(3265 935);
DISPLAY 0.680851 (3265 935);
PAINT MONO (3265 935);
FORCEPROP 0 LASTPIN (3275 975) $PN B30
J 2
(3265 985);
DISPLAY 0.680851 (3265 985);
PAINT MONO (3265 985);
FORCEPROP 0 LASTPIN (3275 1025) $PN B36
J 2
(3265 1035);
DISPLAY 0.680851 (3265 1035);
PAINT MONO (3265 1035);
FORCEPROP 0 LASTPIN (3275 1075) $PN B42
J 2
(3265 1085);
DISPLAY 0.680851 (3265 1085);
PAINT MONO (3265 1085);
FORCEPROP 0 LASTPIN (3275 1125) $PN B49
J 2
(3265 1135);
DISPLAY 0.680851 (3265 1135);
PAINT MONO (3265 1135);
FORCEPROP 0 LASTPIN (3275 1175) $PN B55
J 2
(3265 1185);
DISPLAY 0.680851 (3265 1185);
PAINT MONO (3265 1185);
FORCEPROP 0 LASTPIN (3275 775) $PN B6
J 2
(3265 785);
DISPLAY 0.680851 (3265 785);
PAINT MONO (3265 785);
FORCEPROP 0 LASTPIN (3275 1225) $PN B61
J 2
(3265 1235);
DISPLAY 0.680851 (3265 1235);
PAINT MONO (3265 1235);
FORCEPROP 0 LASTPIN (3275 1275) $PN B67
J 2
(3265 1285);
DISPLAY 0.680851 (3265 1285);
PAINT MONO (3265 1285);
FORCEPROP 0 LASTPIN (3275 1325) $PN B75
J 2
(3265 1335);
DISPLAY 0.680851 (3265 1335);
PAINT MONO (3265 1335);
FORCEPROP 0 LASTPIN (3275 1375) $PN B83
J 2
(3265 1385);
DISPLAY 0.680851 (3265 1385);
PAINT MONO (3265 1385);
FORCEPROP 0 LASTPIN (3275 1425) $PN B87
J 2
(3265 1435);
DISPLAY 0.680851 (3265 1435);
PAINT MONO (3265 1435);
FORCEPROP 0 LASTPIN (3275 1525) $PN C39
J 2
(3265 1535);
DISPLAY 0.680851 (3265 1535);
PAINT MONO (3265 1535);
FORCEPROP 0 LASTPIN (3275 1575) $PN C45
J 2
(3265 1585);
DISPLAY 0.680851 (3265 1585);
PAINT MONO (3265 1585);
FORCEPROP 0 LASTPIN (3275 1475) $PN C5
J 2
(3265 1485);
DISPLAY 0.680851 (3265 1485);
PAINT MONO (3265 1485);
FORCEPROP 0 LASTPIN (3275 1625) $PN C52
J 2
(3265 1635);
DISPLAY 0.680851 (3265 1635);
PAINT MONO (3265 1635);
FORCEPROP 0 LASTPIN (3275 1675) $PN C72
J 2
(3265 1685);
DISPLAY 0.680851 (3265 1685);
PAINT MONO (3265 1685);
FORCEPROP 0 LASTPIN (3275 1725) $PN C74
J 2
(3265 1735);
DISPLAY 0.680851 (3265 1735);
PAINT MONO (3265 1735);
FORCEPROP 0 LASTPIN (3275 1775) $PN C78
J 2
(3265 1785);
DISPLAY 0.680851 (3265 1785);
PAINT MONO (3265 1785);
FORCEPROP 0 LASTPIN (3275 1825) $PN C80
J 2
(3265 1835);
DISPLAY 0.680851 (3265 1835);
PAINT MONO (3265 1835);
FORCEPROP 0 LASTPIN (3275 1875) $PN C82
J 2
(3265 1885);
DISPLAY 0.680851 (3265 1885);
PAINT MONO (3265 1885);
FORCEPROP 0 LASTPIN (3275 1925) $PN C86
J 2
(3265 1935);
DISPLAY 0.680851 (3265 1935);
PAINT MONO (3265 1935);
FORCEPROP 0 LASTPIN (3275 3375) $PN D63
J 2
(3265 3385);
DISPLAY 0.680851 (3265 3385);
PAINT MONO (3265 3385);
FORCEPROP 0 LASTPIN (3275 3425) $PN D65
J 2
(3265 3435);
DISPLAY 0.680851 (3265 3435);
PAINT MONO (3265 3435);
FORCEPROP 0 LASTPIN (3275 3475) $PN D67
J 2
(3265 3485);
DISPLAY 0.680851 (3265 3485);
PAINT MONO (3265 3485);
FORCEPROP 0 LASTPIN (3275 3625) $PN D79
J 2
(3265 3635);
DISPLAY 0.680851 (3265 3635);
PAINT MONO (3265 3635);
FORCEPROP 0 LASTPIN (3275 2025) $PN D8
J 2
(3265 2035);
DISPLAY 0.680851 (3265 2035);
PAINT MONO (3265 2035);
FORCEPROP 0 LASTPIN (3275 2075) $PN D10
J 2
(3265 2085);
DISPLAY 0.680851 (3265 2085);
PAINT MONO (3265 2085);
FORCEPROP 0 LASTPIN (3275 2125) $PN D12
J 2
(3265 2135);
DISPLAY 0.680851 (3265 2135);
PAINT MONO (3265 2135);
FORCEPROP 0 LASTPIN (3275 2175) $PN D14
J 2
(3265 2185);
DISPLAY 0.680851 (3265 2185);
PAINT MONO (3265 2185);
FORCEPROP 0 LASTPIN (3275 2225) $PN D16
J 2
(3265 2235);
DISPLAY 0.680851 (3265 2235);
PAINT MONO (3265 2235);
FORCEPROP 0 LASTPIN (3275 2275) $PN D18
J 2
(3265 2285);
DISPLAY 0.680851 (3265 2285);
PAINT MONO (3265 2285);
FORCEPROP 0 LASTPIN (3275 2325) $PN D20
J 2
(3265 2335);
DISPLAY 0.680851 (3265 2335);
PAINT MONO (3265 2335);
FORCEPROP 0 LASTPIN (3275 2375) $PN D22
J 2
(3265 2385);
DISPLAY 0.680851 (3265 2385);
PAINT MONO (3265 2385);
FORCEPROP 0 LASTPIN (3275 2425) $PN D24
J 2
(3265 2435);
DISPLAY 0.680851 (3265 2435);
PAINT MONO (3265 2435);
FORCEPROP 0 LASTPIN (3275 2475) $PN D26
J 2
(3265 2485);
DISPLAY 0.680851 (3265 2485);
PAINT MONO (3265 2485);
FORCEPROP 0 LASTPIN (3275 2525) $PN D28
J 2
(3265 2535);
DISPLAY 0.680851 (3265 2535);
PAINT MONO (3265 2535);
FORCEPROP 0 LASTPIN (3275 2575) $PN D30
J 2
(3265 2585);
DISPLAY 0.680851 (3265 2585);
PAINT MONO (3265 2585);
FORCEPROP 0 LASTPIN (3275 2625) $PN D32
J 2
(3265 2635);
DISPLAY 0.680851 (3265 2635);
PAINT MONO (3265 2635);
FORCEPROP 0 LASTPIN (3275 2675) $PN D34
J 2
(3265 2685);
DISPLAY 0.680851 (3265 2685);
PAINT MONO (3265 2685);
FORCEPROP 0 LASTPIN (3275 2725) $PN D36
J 2
(3265 2735);
DISPLAY 0.680851 (3265 2735);
PAINT MONO (3265 2735);
FORCEPROP 0 LASTPIN (3275 2775) $PN D38
J 2
(3265 2785);
DISPLAY 0.680851 (3265 2785);
PAINT MONO (3265 2785);
FORCEPROP 0 LASTPIN (3275 2825) $PN D40
J 2
(3265 2835);
DISPLAY 0.680851 (3265 2835);
PAINT MONO (3265 2835);
FORCEPROP 0 LASTPIN (3275 2875) $PN D42
J 2
(3265 2885);
DISPLAY 0.680851 (3265 2885);
PAINT MONO (3265 2885);
FORCEPROP 0 LASTPIN (3275 2925) $PN D44
J 2
(3265 2935);
DISPLAY 0.680851 (3265 2935);
PAINT MONO (3265 2935);
FORCEPROP 0 LASTPIN (3275 2975) $PN D47
J 2
(3265 2985);
DISPLAY 0.680851 (3265 2985);
PAINT MONO (3265 2985);
FORCEPROP 0 LASTPIN (3275 3025) $PN D49
J 2
(3265 3035);
DISPLAY 0.680851 (3265 3035);
PAINT MONO (3265 3035);
FORCEPROP 0 LASTPIN (3275 3075) $PN D51
J 2
(3265 3085);
DISPLAY 0.680851 (3265 3085);
PAINT MONO (3265 3085);
FORCEPROP 0 LASTPIN (3275 3125) $PN D53
J 2
(3265 3135);
DISPLAY 0.680851 (3265 3135);
PAINT MONO (3265 3135);
FORCEPROP 0 LASTPIN (3275 3175) $PN D55
J 2
(3265 3185);
DISPLAY 0.680851 (3265 3185);
PAINT MONO (3265 3185);
FORCEPROP 0 LASTPIN (3275 3225) $PN D57
J 2
(3265 3235);
DISPLAY 0.680851 (3265 3235);
PAINT MONO (3265 3235);
FORCEPROP 0 LASTPIN (3275 3275) $PN D59
J 2
(3265 3285);
DISPLAY 0.680851 (3265 3285);
PAINT MONO (3265 3285);
FORCEPROP 0 LASTPIN (3275 1975) $PN D6
J 2
(3265 1985);
DISPLAY 0.680851 (3265 1985);
PAINT MONO (3265 1985);
FORCEPROP 0 LASTPIN (3275 3325) $PN D61
J 2
(3265 3335);
DISPLAY 0.680851 (3265 3335);
PAINT MONO (3265 3335);
FORCEPROP 0 LASTPIN (3275 3525) $PN D69
J 2
(3265 3535);
DISPLAY 0.680851 (3265 3535);
PAINT MONO (3265 3535);
FORCEPROP 0 LASTPIN (3275 3575) $PN D71
J 2
(3265 3585);
DISPLAY 0.680851 (3265 3585);
PAINT MONO (3265 3585);
FORCEPROP 0 LASTPIN (3275 3675) $PN D81
J 2
(3265 3685);
DISPLAY 0.680851 (3265 3685);
PAINT MONO (3265 3685);
FORCEPROP 0 LASTPIN (3275 3725) $PN D83
J 2
(3265 3735);
DISPLAY 0.680851 (3265 3735);
PAINT MONO (3265 3735);
FORCEPROP 0 LASTPIN (3275 3775) $PN E5
J 2
(3265 3785);
DISPLAY 0.680851 (3265 3785);
PAINT MONO (3265 3785);
FORCEPROP 0 LASTPIN (3275 3825) $PN E39
J 2
(3265 3835);
DISPLAY 0.680851 (3265 3835);
PAINT MONO (3265 3835);
FORCEPROP 2 LAST CDS_LIB pure_quanta
J 0
(4475 1900);
DISPLAY INVISIBLE (4475 1900);
FORCEPROP 1 LAST NEEDS_NO_SIZE TRUE
J 0
(4475 1900);
DISPLAY 0.723404 (4475 1900);
PAINT GREEN (4475 1900);
DISPLAY INVISIBLE (4475 1900);
FORCEPROP 1 LAST CDS_LMAN_SYM_OUTLINE -1050,2100,1050,-2050
J 0
(4475 1900);
DISPLAY 0.468085 (4475 1900);
PAINT GREEN (4475 1900);
DISPLAY INVISIBLE (4475 1900);
FORCEPROP 0 LAST CDS_LOCATION U1
J 0
(3425 4325);
DISPLAY 1.021277 (3425 4325);
DISPLAY INVISIBLE (3425 4325);
FORCEPROP 0 LAST $SEC 42
J 0
(3425 4325);
DISPLAY 0.680851 (3425 4325);
PAINT MONO (3425 4325);
DISPLAY INVISIBLE (3425 4325);
FORCEPROP 2 LAST CDS_SEC 42
J 0
(3425 4325);
DISPLAY 1.021277 (3425 4325);
DISPLAY INVISIBLE (3425 4325);
FORCEPROP 1 LAST PATH I8
J 0
(4475 1900);
DISPLAY 0.723404 (4475 1900);
PAINT GREEN (4475 1900);
DISPLAY INVISIBLE (4475 1900);
FORCEADD QUANTA_TITLE_BLOCK_C..1
(5900 -1525);
FORCEPROP 0 LAST CDS_CON_LAST_MODIFIED Fri Aug 25 14:00:53 2023
J 0
(4015 -1510);
PAINT MONO (4015 -1510);
DISPLAY INVISIBLE (4015 -1510);
FORCEPROP 1 LAST CUSTOM_TXT_CDS <CON_LAST_MODIFIED>
J 0
(4015 -1510);
DISPLAY 0.978723 (4015 -1510);
FORCEPROP 2 LAST CUSTOM_TXT_CDS <XR_PAGE_TITLE>
J 0
(-1990 3725);
DISPLAY 0.638298 (-1990 3725);
PAINT PINK (-1990 3725);
DISPLAY INVISIBLE (-1990 3725);
FORCEPROP 2 LAST CUSTOM_TXT_CDS <Q_NUMBER>
J 0
(4497 -1422);
DISPLAY 1.212766 (4497 -1422);
FORCEPROP 1 LAST CUSTOM_TXT_CDS <NAME_2>
J 0
(2725 -1475);
FORCEPROP 1 LAST CUSTOM_TXT_CDS <NAME_1>
J 0
(2725 -1350);
FORCEPROP 1 LAST CUSTOM_TXT_CDS <Q_PROJ>
J 0
(3518 -1423);
DISPLAY 1.212766 (3518 -1423);
FORCEPROP 1 LAST CUSTOM_TXT_CDS <Q_REV>
J 0
(5716 -1422);
DISPLAY 1.212766 (5716 -1422);
FORCEPROP 1 LAST CUSTOM_TXT_CDS <CON_PAGE_NUM> OF <CON_TOTAL_PAGES>
J 0
(5454 -1507);
DISPLAY 0.978723 (5454 -1507);
FORCEPROP 1 LAST Q_TITLE SPR CPU1 POWER - GND (30 OF 30)
J 0
(-3466 -1499);
DISPLAY 1.957447 (-3466 -1499);
PAINT GREEN (-3466 -1499);
FORCEPROP 1 LAST Q_DEPT 
J 1
(2137 -1476);
DISPLAY 1.957447 (2137 -1476);
PAINT GREEN (2137 -1476);
FORCEPROP 1 LAST COMMENT_BODY TRUE
J 0
(5912 -1538);
DISPLAY 0.978723 (5912 -1538);
PAINT GREEN (5912 -1538);
DISPLAY INVISIBLE (5912 -1538);
FORCEPROP 2 LAST CDS_XR_PAGE_TITLE CR-73 : @S9S_MB_2U_LIB.S9S_MB_2U(SCH_1):PAGE73
J 0
(-1990 3725);
DISPLAY 0.638298 (-1990 3725);
PAINT PINK (-1990 3725);
DISPLAY INVISIBLE (-1990 3725);
FORCEPROP 2 LAST CDS_LIB pure_quanta
J 0
(5900 -1525);
PAINT MONO (5900 -1525);
DISPLAY INVISIBLE (5900 -1525);
FORCEPROP 1 LAST CDS_LMAN_SYM_OUTLINE -9475,6775,100,-125
J 0
(5900 -1525);
DISPLAY 0.468085 (5900 -1525);
PAINT GREEN (5900 -1525);
DISPLAY INVISIBLE (5900 -1525);
FORCEPROP 2 LAST PAGE_BORDER TRUE
J 0
(-1990 3725);
DISPLAY 0.638298 (-1990 3725);
PAINT PINK (-1990 3725);
DISPLAY INVISIBLE (-1990 3725);
WIRE 16 -1 (3025 -25)(3025 -625);
WIRE 16 -1 (3025 25)(3025 -25);
WIRE 16 -1 (3025 -25)(3275 -25);
WIRE 16 -1 (2900 75)(2900 -625);
WIRE 16 -1 (2900 125)(2900 75);
WIRE 16 -1 (2650 75)(2900 75);
WIRE 16 -1 (0 -125)(0 -625);
WIRE 16 -1 (0 -75)(0 -125);
WIRE 16 -1 (0 -125)(250 -125);
WIRE 16 -1 (-150 -125)(-150 -625);
WIRE 16 -1 (-150 -75)(-150 -125);
WIRE 16 -1 (-400 -125)(-150 -125);
WIRE 16 -1 (-3050 -125)(-3050 -625);
WIRE 16 -1 (-3050 -75)(-3050 -125);
WIRE 16 -1 (-3050 -125)(-2800 -125);
WIRE 16 -1 (-2800 3825)(-3050 3825);
WIRE 16 -1 (-3050 3825)(-3050 3775);
WIRE 16 -1 (-2800 3775)(-3050 3775);
WIRE 16 -1 (-3050 3775)(-3050 3725);
WIRE 16 -1 (-2800 3725)(-3050 3725);
WIRE 16 -1 (-3050 3725)(-3050 3675);
WIRE 16 -1 (-2800 3675)(-3050 3675);
WIRE 16 -1 (-3050 3675)(-3050 3625);
WIRE 16 -1 (-2800 3625)(-3050 3625);
WIRE 16 -1 (-2800 3575)(-3050 3575);
WIRE 16 -1 (-3050 3625)(-3050 3575);
WIRE 16 -1 (-3050 3575)(-3050 3525);
WIRE 16 -1 (-2800 3525)(-3050 3525);
WIRE 16 -1 (-3050 3525)(-3050 3475);
WIRE 16 -1 (-2800 3475)(-3050 3475);
WIRE 16 -1 (-3050 3475)(-3050 3425);
WIRE 16 -1 (-2800 3425)(-3050 3425);
WIRE 16 -1 (-3050 3425)(-3050 3375);
WIRE 16 -1 (-2800 3375)(-3050 3375);
WIRE 16 -1 (-3050 3375)(-3050 3325);
WIRE 16 -1 (-2800 3325)(-3050 3325);
WIRE 16 -1 (-3050 3325)(-3050 3275);
WIRE 16 -1 (-2800 3275)(-3050 3275);
WIRE 16 -1 (-3050 3275)(-3050 3225);
WIRE 16 -1 (-2800 3225)(-3050 3225);
WIRE 16 -1 (-3050 3225)(-3050 3175);
WIRE 16 -1 (-2800 3175)(-3050 3175);
WIRE 16 -1 (-3050 3175)(-3050 3125);
WIRE 16 -1 (-3050 3125)(-2800 3125);
WIRE 16 -1 (-3050 3125)(-3050 3075);
WIRE 16 -1 (-3050 3075)(-2800 3075);
WIRE 16 -1 (-3050 3025)(-2800 3025);
WIRE 16 -1 (-3050 3075)(-3050 3025);
WIRE 16 -1 (-3050 3025)(-3050 2975);
WIRE 16 -1 (-3050 2975)(-2800 2975);
WIRE 16 -1 (-3050 2975)(-3050 2925);
WIRE 16 -1 (-3050 2925)(-2800 2925);
WIRE 16 -1 (-3050 2925)(-3050 2875);
WIRE 16 -1 (-3050 2875)(-2800 2875);
WIRE 16 -1 (-3050 2875)(-3050 2825);
WIRE 16 -1 (-3050 2825)(-2800 2825);
WIRE 16 -1 (-3050 2825)(-3050 2775);
WIRE 16 -1 (-3050 2775)(-2800 2775);
WIRE 16 -1 (-3050 2775)(-3050 2725);
WIRE 16 -1 (-3050 2725)(-2800 2725);
WIRE 16 -1 (-3050 2725)(-3050 2675);
WIRE 16 -1 (-3050 2675)(-2800 2675);
WIRE 16 -1 (-3050 2675)(-3050 2625);
WIRE 16 -1 (-3050 2625)(-2800 2625);
WIRE 16 -1 (-3050 2625)(-3050 2575);
WIRE 16 -1 (-3050 2575)(-2800 2575);
WIRE 16 -1 (-3050 2525)(-2800 2525);
WIRE 16 -1 (-3050 2575)(-3050 2525);
WIRE 16 -1 (-3050 2525)(-3050 2475);
WIRE 16 -1 (-3050 2475)(-2800 2475);
WIRE 16 -1 (-3050 2475)(-3050 2425);
WIRE 16 -1 (-3050 2425)(-2800 2425);
WIRE 16 -1 (-3050 2425)(-3050 2375);
WIRE 16 -1 (-3050 2375)(-2800 2375);
WIRE 16 -1 (-3050 2375)(-3050 2325);
WIRE 16 -1 (-3050 2325)(-2800 2325);
WIRE 16 -1 (-3050 2325)(-3050 2275);
WIRE 16 -1 (-3050 2275)(-2800 2275);
WIRE 16 -1 (-3050 2275)(-3050 2225);
WIRE 16 -1 (-3050 2225)(-2800 2225);
WIRE 16 -1 (-3050 2225)(-3050 2175);
WIRE 16 -1 (-3050 2175)(-2800 2175);
WIRE 16 -1 (-3050 2175)(-3050 2125);
WIRE 16 -1 (-3050 2125)(-2800 2125);
WIRE 16 -1 (-3050 2125)(-3050 2075);
WIRE 16 -1 (-3050 2075)(-2800 2075);
WIRE 16 -1 (-3050 2025)(-2800 2025);
WIRE 16 -1 (-3050 2075)(-3050 2025);
WIRE 16 -1 (-3050 2025)(-3050 1975);
WIRE 16 -1 (-3050 1975)(-2800 1975);
WIRE 16 -1 (-3050 1975)(-3050 1925);
WIRE 16 -1 (-3050 1925)(-2800 1925);
WIRE 16 -1 (-3050 1925)(-3050 1875);
WIRE 16 -1 (-3050 1875)(-2800 1875);
WIRE 16 -1 (-3050 1875)(-3050 1825);
WIRE 16 -1 (-3050 1825)(-2800 1825);
WIRE 16 -1 (-3050 1825)(-3050 1775);
WIRE 16 -1 (-2800 1775)(-3050 1775);
WIRE 16 -1 (-3050 1775)(-3050 1725);
WIRE 16 -1 (-3050 1725)(-2800 1725);
WIRE 16 -1 (-3050 1725)(-3050 1675);
WIRE 16 -1 (-3050 1675)(-2800 1675);
WIRE 16 -1 (-3050 1675)(-3050 1625);
WIRE 16 -1 (-3050 1625)(-2800 1625);
WIRE 16 -1 (-3050 1625)(-3050 1575);
WIRE 16 -1 (-3050 1575)(-2800 1575);
WIRE 16 -1 (-3050 1525)(-2800 1525);
WIRE 16 -1 (-3050 1575)(-3050 1525);
WIRE 16 -1 (-3050 1525)(-3050 1475);
WIRE 16 -1 (-3050 1475)(-2800 1475);
WIRE 16 -1 (-3050 1475)(-3050 1425);
WIRE 16 -1 (-3050 1425)(-2800 1425);
WIRE 16 -1 (-3050 1425)(-3050 1375);
WIRE 16 -1 (-3050 1375)(-2800 1375);
WIRE 16 -1 (-3050 1375)(-3050 1325);
WIRE 16 -1 (-3050 1325)(-2800 1325);
WIRE 16 -1 (-3050 1325)(-3050 1275);
WIRE 16 -1 (-3050 1275)(-2800 1275);
WIRE 16 -1 (-3050 1275)(-3050 1225);
WIRE 16 -1 (-3050 1225)(-2800 1225);
WIRE 16 -1 (-3050 1225)(-3050 1175);
WIRE 16 -1 (-3050 1175)(-2800 1175);
WIRE 16 -1 (-3050 1175)(-3050 1125);
WIRE 16 -1 (-3050 1125)(-2800 1125);
WIRE 16 -1 (-3050 1125)(-3050 1075);
WIRE 16 -1 (-3050 1075)(-2800 1075);
WIRE 16 -1 (-3050 1075)(-3050 1025);
WIRE 16 -1 (-3050 1025)(-2800 1025);
WIRE 16 -1 (-3050 975)(-2800 975);
WIRE 16 -1 (-3050 1025)(-3050 975);
WIRE 16 -1 (-3050 975)(-3050 925);
WIRE 16 -1 (-3050 925)(-2800 925);
WIRE 16 -1 (-3050 925)(-3050 875);
WIRE 16 -1 (-3050 875)(-2800 875);
WIRE 16 -1 (-3050 875)(-3050 825);
WIRE 16 -1 (-3050 825)(-2800 825);
WIRE 16 -1 (-3050 825)(-3050 775);
WIRE 16 -1 (-2800 775)(-3050 775);
WIRE 16 -1 (-3050 775)(-3050 725);
WIRE 16 -1 (-3050 725)(-2800 725);
WIRE 16 -1 (-3050 725)(-3050 675);
WIRE 16 -1 (-3050 675)(-2800 675);
WIRE 16 -1 (-3050 675)(-3050 625);
WIRE 16 -1 (-3050 625)(-2800 625);
WIRE 16 -1 (-3050 625)(-3050 575);
WIRE 16 -1 (-3050 575)(-2800 575);
WIRE 16 -1 (-3050 575)(-3050 525);
WIRE 16 -1 (-3050 525)(-2800 525);
WIRE 16 -1 (-2800 475)(-3050 475);
WIRE 16 -1 (-3050 525)(-3050 475);
WIRE 16 -1 (-3050 475)(-3050 425);
WIRE 16 -1 (-3050 425)(-2800 425);
WIRE 16 -1 (-3050 425)(-3050 375);
WIRE 16 -1 (-3050 375)(-2800 375);
WIRE 16 -1 (-3050 375)(-3050 325);
WIRE 16 -1 (-3050 325)(-2800 325);
WIRE 16 -1 (-3050 325)(-3050 275);
WIRE 16 -1 (-3050 275)(-2800 275);
WIRE 16 -1 (-3050 275)(-3050 225);
WIRE 16 -1 (-3050 225)(-2800 225);
WIRE 16 -1 (-3050 225)(-3050 175);
WIRE 16 -1 (-3050 175)(-2800 175);
WIRE 16 -1 (-3050 175)(-3050 125);
WIRE 16 -1 (-2800 125)(-3050 125);
WIRE 16 -1 (-3050 125)(-3050 75);
WIRE 16 -1 (-3050 75)(-2800 75);
WIRE 16 -1 (-3050 75)(-3050 25);
WIRE 16 -1 (-3050 25)(-2800 25);
WIRE 16 -1 (-3050 -25)(-2800 -25);
WIRE 16 -1 (-3050 25)(-3050 -25);
WIRE 16 -1 (-3050 -25)(-3050 -75);
WIRE 16 -1 (-3050 -75)(-2800 -75);
WIRE 16 -1 (-150 3825)(-400 3825);
WIRE 16 -1 (-150 3775)(-400 3775);
WIRE 16 -1 (-150 3825)(-150 3775);
WIRE 16 -1 (-150 3725)(-400 3725);
WIRE 16 -1 (-150 3775)(-150 3725);
WIRE 16 -1 (-150 3675)(-400 3675);
WIRE 16 -1 (-150 3725)(-150 3675);
WIRE 16 -1 (-400 3625)(-150 3625);
WIRE 16 -1 (-150 3625)(-150 3675);
WIRE 16 -1 (-150 3575)(-400 3575);
WIRE 16 -1 (-150 3575)(-150 3625);
WIRE 16 -1 (-150 3525)(-400 3525);
WIRE 16 -1 (-150 3575)(-150 3525);
WIRE 16 -1 (-150 3475)(-400 3475);
WIRE 16 -1 (-150 3525)(-150 3475);
WIRE 16 -1 (-150 3425)(-400 3425);
WIRE 16 -1 (-150 3475)(-150 3425);
WIRE 16 -1 (-150 3375)(-400 3375);
WIRE 16 -1 (-150 3425)(-150 3375);
WIRE 16 -1 (-150 3325)(-400 3325);
WIRE 16 -1 (-150 3375)(-150 3325);
WIRE 16 -1 (-150 3275)(-400 3275);
WIRE 16 -1 (-150 3325)(-150 3275);
WIRE 16 -1 (-150 3225)(-400 3225);
WIRE 16 -1 (-150 3275)(-150 3225);
WIRE 16 -1 (-150 3175)(-400 3175);
WIRE 16 -1 (-150 3225)(-150 3175);
WIRE 16 -1 (-400 3125)(-150 3125);
WIRE 16 -1 (-150 3175)(-150 3125);
WIRE 16 -1 (-400 3075)(-150 3075);
WIRE 16 -1 (-150 3125)(-150 3075);
WIRE 16 -1 (-400 3025)(-150 3025);
WIRE 16 -1 (-150 3075)(-150 3025);
WIRE 16 -1 (-400 2975)(-150 2975);
WIRE 16 -1 (-150 3025)(-150 2975);
WIRE 16 -1 (-400 2925)(-150 2925);
WIRE 16 -1 (-150 2975)(-150 2925);
WIRE 16 -1 (-400 2875)(-150 2875);
WIRE 16 -1 (-150 2925)(-150 2875);
WIRE 16 -1 (-400 2825)(-150 2825);
WIRE 16 -1 (-150 2875)(-150 2825);
WIRE 16 -1 (-400 2775)(-150 2775);
WIRE 16 -1 (-150 2775)(-150 2825);
WIRE 16 -1 (-400 2725)(-150 2725);
WIRE 16 -1 (-150 2775)(-150 2725);
WIRE 16 -1 (-150 2675)(-400 2675);
WIRE 16 -1 (-150 2725)(-150 2675);
WIRE 16 -1 (-150 2625)(-400 2625);
WIRE 16 -1 (-150 2675)(-150 2625);
WIRE 16 -1 (-150 2575)(-400 2575);
WIRE 16 -1 (-150 2625)(-150 2575);
WIRE 16 -1 (-150 2525)(-400 2525);
WIRE 16 -1 (-150 2575)(-150 2525);
WIRE 16 -1 (-400 2475)(-150 2475);
WIRE 16 -1 (-150 2475)(-150 2525);
WIRE 16 -1 (-150 2425)(-400 2425);
WIRE 16 -1 (-150 2425)(-150 2475);
WIRE 16 -1 (-150 2375)(-400 2375);
WIRE 16 -1 (-150 2425)(-150 2375);
WIRE 16 -1 (-150 2325)(-400 2325);
WIRE 16 -1 (-150 2375)(-150 2325);
WIRE 16 -1 (-150 2275)(-400 2275);
WIRE 16 -1 (-150 2325)(-150 2275);
WIRE 16 -1 (-150 2225)(-400 2225);
WIRE 16 -1 (-150 2275)(-150 2225);
WIRE 16 -1 (-150 2175)(-400 2175);
WIRE 16 -1 (-150 2225)(-150 2175);
WIRE 16 -1 (-150 2125)(-400 2125);
WIRE 16 -1 (-150 2175)(-150 2125);
WIRE 16 -1 (-150 2075)(-400 2075);
WIRE 16 -1 (-150 2125)(-150 2075);
WIRE 16 -1 (-150 2025)(-400 2025);
WIRE 16 -1 (-150 2075)(-150 2025);
WIRE 16 -1 (-400 1975)(-150 1975);
WIRE 16 -1 (-150 2025)(-150 1975);
WIRE 16 -1 (-400 1925)(-150 1925);
WIRE 16 -1 (-150 1975)(-150 1925);
WIRE 16 -1 (-400 1875)(-150 1875);
WIRE 16 -1 (-150 1925)(-150 1875);
WIRE 16 -1 (-400 1825)(-150 1825);
WIRE 16 -1 (-150 1875)(-150 1825);
WIRE 16 -1 (-400 1775)(-150 1775);
WIRE 16 -1 (-150 1825)(-150 1775);
WIRE 16 -1 (-400 1725)(-150 1725);
WIRE 16 -1 (-150 1775)(-150 1725);
WIRE 16 -1 (-400 1675)(-150 1675);
WIRE 16 -1 (-150 1725)(-150 1675);
WIRE 16 -1 (-400 1625)(-150 1625);
WIRE 16 -1 (-150 1625)(-150 1675);
WIRE 16 -1 (-400 1575)(-150 1575);
WIRE 16 -1 (-150 1625)(-150 1575);
WIRE 16 -1 (-150 1525)(-400 1525);
WIRE 16 -1 (-150 1575)(-150 1525);
WIRE 16 -1 (-150 1475)(-400 1475);
WIRE 16 -1 (-150 1525)(-150 1475);
WIRE 16 -1 (-150 1425)(-400 1425);
WIRE 16 -1 (-150 1475)(-150 1425);
WIRE 16 -1 (-150 1375)(-400 1375);
WIRE 16 -1 (-150 1425)(-150 1375);
WIRE 16 -1 (-400 1325)(-150 1325);
WIRE 16 -1 (-150 1325)(-150 1375);
WIRE 16 -1 (-150 1275)(-400 1275);
WIRE 16 -1 (-150 1275)(-150 1325);
WIRE 16 -1 (-150 1225)(-400 1225);
WIRE 16 -1 (-150 1275)(-150 1225);
WIRE 16 -1 (-150 1175)(-400 1175);
WIRE 16 -1 (-150 1225)(-150 1175);
WIRE 16 -1 (-400 1125)(-150 1125);
WIRE 16 -1 (-150 1175)(-150 1125);
WIRE 16 -1 (-400 1075)(-150 1075);
WIRE 16 -1 (-150 1125)(-150 1075);
WIRE 16 -1 (-400 1025)(-150 1025);
WIRE 16 -1 (-150 1075)(-150 1025);
WIRE 16 -1 (-400 975)(-150 975);
WIRE 16 -1 (-150 1025)(-150 975);
WIRE 16 -1 (-400 925)(-150 925);
WIRE 16 -1 (-150 975)(-150 925);
WIRE 16 -1 (-400 875)(-150 875);
WIRE 16 -1 (-150 925)(-150 875);
WIRE 16 -1 (-400 825)(-150 825);
WIRE 16 -1 (-150 875)(-150 825);
WIRE 16 -1 (-400 775)(-150 775);
WIRE 16 -1 (-150 775)(-150 825);
WIRE 16 -1 (-400 725)(-150 725);
WIRE 16 -1 (-150 775)(-150 725);
WIRE 16 -1 (-150 675)(-400 675);
WIRE 16 -1 (-150 725)(-150 675);
WIRE 16 -1 (-150 625)(-400 625);
WIRE 16 -1 (-150 675)(-150 625);
WIRE 16 -1 (-150 575)(-400 575);
WIRE 16 -1 (-150 625)(-150 575);
WIRE 16 -1 (-150 525)(-400 525);
WIRE 16 -1 (-150 575)(-150 525);
WIRE 16 -1 (-400 475)(-150 475);
WIRE 16 -1 (-150 475)(-150 525);
WIRE 16 -1 (-150 425)(-400 425);
WIRE 16 -1 (-150 425)(-150 475);
WIRE 16 -1 (-150 375)(-400 375);
WIRE 16 -1 (-150 425)(-150 375);
WIRE 16 -1 (-150 325)(-400 325);
WIRE 16 -1 (-150 375)(-150 325);
WIRE 16 -1 (-400 275)(-150 275);
WIRE 16 -1 (-150 325)(-150 275);
WIRE 16 -1 (-400 225)(-150 225);
WIRE 16 -1 (-150 275)(-150 225);
WIRE 16 -1 (-400 175)(-150 175);
WIRE 16 -1 (-150 225)(-150 175);
WIRE 16 -1 (-400 125)(-150 125);
WIRE 16 -1 (-150 175)(-150 125);
WIRE 16 -1 (-400 75)(-150 75);
WIRE 16 -1 (-150 125)(-150 75);
WIRE 16 -1 (-400 25)(-150 25);
WIRE 16 -1 (-150 75)(-150 25);
WIRE 16 -1 (-400 -25)(-150 -25);
WIRE 16 -1 (-150 25)(-150 -25);
WIRE 16 -1 (-150 -75)(-150 -25);
WIRE 16 -1 (-400 -75)(-150 -75);
WIRE 16 -1 (250 3825)(0 3825);
WIRE 16 -1 (0 3825)(0 3775);
WIRE 16 -1 (250 3775)(0 3775);
WIRE 16 -1 (0 3775)(0 3725);
WIRE 16 -1 (250 3725)(0 3725);
WIRE 16 -1 (0 3725)(0 3675);
WIRE 16 -1 (250 3675)(0 3675);
WIRE 16 -1 (0 3675)(0 3625);
WIRE 16 -1 (250 3625)(0 3625);
WIRE 16 -1 (0 3625)(0 3575);
WIRE 16 -1 (250 3575)(0 3575);
WIRE 16 -1 (0 3575)(0 3525);
WIRE 16 -1 (250 3525)(0 3525);
WIRE 16 -1 (0 3525)(0 3475);
WIRE 16 -1 (250 3475)(0 3475);
WIRE 16 -1 (0 3475)(0 3425);
WIRE 16 -1 (250 3425)(0 3425);
WIRE 16 -1 (0 3425)(0 3375);
WIRE 16 -1 (250 3375)(0 3375);
WIRE 16 -1 (0 3375)(0 3325);
WIRE 16 -1 (250 3325)(0 3325);
WIRE 16 -1 (0 3325)(0 3275);
WIRE 16 -1 (250 3275)(0 3275);
WIRE 16 -1 (0 3275)(0 3225);
WIRE 16 -1 (250 3225)(0 3225);
WIRE 16 -1 (0 3225)(0 3175);
WIRE 16 -1 (250 3175)(0 3175);
WIRE 16 -1 (0 3175)(0 3125);
WIRE 16 -1 (0 3125)(250 3125);
WIRE 16 -1 (0 3125)(0 3075);
WIRE 16 -1 (0 3075)(250 3075);
WIRE 16 -1 (0 3075)(0 3025);
WIRE 16 -1 (0 3025)(250 3025);
WIRE 16 -1 (0 3025)(0 2975);
WIRE 16 -1 (0 2975)(250 2975);
WIRE 16 -1 (0 2975)(0 2925);
WIRE 16 -1 (0 2925)(250 2925);
WIRE 16 -1 (0 2925)(0 2875);
WIRE 16 -1 (0 2875)(250 2875);
WIRE 16 -1 (0 2875)(0 2825);
WIRE 16 -1 (0 2825)(250 2825);
WIRE 16 -1 (0 2825)(0 2775);
WIRE 16 -1 (0 2775)(250 2775);
WIRE 16 -1 (0 2775)(0 2725);
WIRE 16 -1 (0 2725)(250 2725);
WIRE 16 -1 (0 2725)(0 2675);
WIRE 16 -1 (0 2675)(250 2675);
WIRE 16 -1 (0 2675)(0 2625);
WIRE 16 -1 (0 2625)(250 2625);
WIRE 16 -1 (0 2625)(0 2575);
WIRE 16 -1 (0 2575)(250 2575);
WIRE 16 -1 (0 2575)(0 2525);
WIRE 16 -1 (0 2525)(250 2525);
WIRE 16 -1 (0 2525)(0 2475);
WIRE 16 -1 (0 2475)(250 2475);
WIRE 16 -1 (0 2475)(0 2425);
WIRE 16 -1 (0 2425)(250 2425);
WIRE 16 -1 (0 2425)(0 2375);
WIRE 16 -1 (0 2375)(250 2375);
WIRE 16 -1 (0 2375)(0 2325);
WIRE 16 -1 (0 2325)(250 2325);
WIRE 16 -1 (0 2325)(0 2275);
WIRE 16 -1 (0 2275)(250 2275);
WIRE 16 -1 (0 2275)(0 2225);
WIRE 16 -1 (0 2225)(250 2225);
WIRE 16 -1 (0 2225)(0 2175);
WIRE 16 -1 (0 2175)(250 2175);
WIRE 16 -1 (0 2175)(0 2125);
WIRE 16 -1 (0 2125)(250 2125);
WIRE 16 -1 (0 2125)(0 2075);
WIRE 16 -1 (0 2075)(250 2075);
WIRE 16 -1 (0 2075)(0 2025);
WIRE 16 -1 (0 2025)(250 2025);
WIRE 16 -1 (0 2025)(0 1975);
WIRE 16 -1 (0 1975)(250 1975);
WIRE 16 -1 (0 1975)(0 1925);
WIRE 16 -1 (0 1925)(250 1925);
WIRE 16 -1 (0 1925)(0 1875);
WIRE 16 -1 (0 1875)(250 1875);
WIRE 16 -1 (0 1875)(0 1825);
WIRE 16 -1 (0 1825)(250 1825);
WIRE 16 -1 (0 1825)(0 1775);
WIRE 16 -1 (250 1775)(0 1775);
WIRE 16 -1 (0 1775)(0 1725);
WIRE 16 -1 (0 1725)(250 1725);
WIRE 16 -1 (0 1725)(0 1675);
WIRE 16 -1 (0 1675)(250 1675);
WIRE 16 -1 (0 1675)(0 1625);
WIRE 16 -1 (0 1625)(250 1625);
WIRE 16 -1 (0 1625)(0 1575);
WIRE 16 -1 (0 1575)(250 1575);
WIRE 16 -1 (0 1575)(0 1525);
WIRE 16 -1 (0 1525)(250 1525);
WIRE 16 -1 (0 1525)(0 1475);
WIRE 16 -1 (0 1475)(250 1475);
WIRE 16 -1 (0 1475)(0 1425);
WIRE 16 -1 (0 1425)(250 1425);
WIRE 16 -1 (0 1425)(0 1375);
WIRE 16 -1 (0 1375)(250 1375);
WIRE 16 -1 (0 1375)(0 1325);
WIRE 16 -1 (0 1325)(250 1325);
WIRE 16 -1 (0 1325)(0 1275);
WIRE 16 -1 (0 1275)(250 1275);
WIRE 16 -1 (0 1275)(0 1225);
WIRE 16 -1 (0 1225)(250 1225);
WIRE 16 -1 (0 1225)(0 1175);
WIRE 16 -1 (0 1175)(250 1175);
WIRE 16 -1 (0 1175)(0 1125);
WIRE 16 -1 (0 1125)(250 1125);
WIRE 16 -1 (0 1125)(0 1075);
WIRE 16 -1 (0 1075)(250 1075);
WIRE 16 -1 (0 1075)(0 1025);
WIRE 16 -1 (0 1025)(250 1025);
WIRE 16 -1 (0 1025)(0 975);
WIRE 16 -1 (0 975)(250 975);
WIRE 16 -1 (0 975)(0 925);
WIRE 16 -1 (0 925)(250 925);
WIRE 16 -1 (0 925)(0 875);
WIRE 16 -1 (0 875)(250 875);
WIRE 16 -1 (0 875)(0 825);
WIRE 16 -1 (0 825)(250 825);
WIRE 16 -1 (0 825)(0 775);
WIRE 16 -1 (250 775)(0 775);
WIRE 16 -1 (0 775)(0 725);
WIRE 16 -1 (0 725)(250 725);
WIRE 16 -1 (0 725)(0 675);
WIRE 16 -1 (0 675)(250 675);
WIRE 16 -1 (0 675)(0 625);
WIRE 16 -1 (0 625)(250 625);
WIRE 16 -1 (0 625)(0 575);
WIRE 16 -1 (0 575)(250 575);
WIRE 16 -1 (0 575)(0 525);
WIRE 16 -1 (0 525)(250 525);
WIRE 16 -1 (0 525)(0 475);
WIRE 16 -1 (250 475)(0 475);
WIRE 16 -1 (0 475)(0 425);
WIRE 16 -1 (0 425)(250 425);
WIRE 16 -1 (0 425)(0 375);
WIRE 16 -1 (0 375)(250 375);
WIRE 16 -1 (0 375)(0 325);
WIRE 16 -1 (0 325)(250 325);
WIRE 16 -1 (0 325)(0 275);
WIRE 16 -1 (0 275)(250 275);
WIRE 16 -1 (0 275)(0 225);
WIRE 16 -1 (0 225)(250 225);
WIRE 16 -1 (0 225)(0 175);
WIRE 16 -1 (0 175)(250 175);
WIRE 16 -1 (0 175)(0 125);
WIRE 16 -1 (250 125)(0 125);
WIRE 16 -1 (0 125)(0 75);
WIRE 16 -1 (0 75)(250 75);
WIRE 16 -1 (0 75)(0 25);
WIRE 16 -1 (0 25)(250 25);
WIRE 16 -1 (0 25)(0 -25);
WIRE 16 -1 (0 -25)(250 -25);
WIRE 16 -1 (0 -25)(0 -75);
WIRE 16 -1 (0 -75)(250 -75);
WIRE 16 -1 (2900 3825)(2650 3825);
WIRE 16 -1 (2900 3775)(2650 3775);
WIRE 16 -1 (2900 3825)(2900 3775);
WIRE 16 -1 (2900 3725)(2650 3725);
WIRE 16 -1 (2900 3775)(2900 3725);
WIRE 16 -1 (2900 3675)(2650 3675);
WIRE 16 -1 (2900 3725)(2900 3675);
WIRE 16 -1 (2650 3625)(2900 3625);
WIRE 16 -1 (2900 3625)(2900 3675);
WIRE 16 -1 (2900 3575)(2650 3575);
WIRE 16 -1 (2900 3575)(2900 3625);
WIRE 16 -1 (2900 3525)(2650 3525);
WIRE 16 -1 (2900 3575)(2900 3525);
WIRE 16 -1 (2900 3475)(2650 3475);
WIRE 16 -1 (2900 3525)(2900 3475);
WIRE 16 -1 (2900 3425)(2650 3425);
WIRE 16 -1 (2900 3475)(2900 3425);
WIRE 16 -1 (2900 3375)(2650 3375);
WIRE 16 -1 (2900 3425)(2900 3375);
WIRE 16 -1 (2900 3325)(2650 3325);
WIRE 16 -1 (2900 3375)(2900 3325);
WIRE 16 -1 (2900 3275)(2650 3275);
WIRE 16 -1 (2900 3325)(2900 3275);
WIRE 16 -1 (2900 3225)(2650 3225);
WIRE 16 -1 (2900 3275)(2900 3225);
WIRE 16 -1 (2900 3175)(2650 3175);
WIRE 16 -1 (2900 3225)(2900 3175);
WIRE 16 -1 (2650 3125)(2900 3125);
WIRE 16 -1 (2900 3175)(2900 3125);
WIRE 16 -1 (2650 3075)(2900 3075);
WIRE 16 -1 (2900 3125)(2900 3075);
WIRE 16 -1 (2650 3025)(2900 3025);
WIRE 16 -1 (2900 3075)(2900 3025);
WIRE 16 -1 (2650 2975)(2900 2975);
WIRE 16 -1 (2900 3025)(2900 2975);
WIRE 16 -1 (2650 2925)(2900 2925);
WIRE 16 -1 (2900 2975)(2900 2925);
WIRE 16 -1 (2650 2875)(2900 2875);
WIRE 16 -1 (2900 2925)(2900 2875);
WIRE 16 -1 (2650 2825)(2900 2825);
WIRE 16 -1 (2900 2875)(2900 2825);
WIRE 16 -1 (2650 2775)(2900 2775);
WIRE 16 -1 (2900 2775)(2900 2825);
WIRE 16 -1 (2650 2725)(2900 2725);
WIRE 16 -1 (2900 2775)(2900 2725);
WIRE 16 -1 (2900 2675)(2650 2675);
WIRE 16 -1 (2900 2725)(2900 2675);
WIRE 16 -1 (2900 2625)(2650 2625);
WIRE 16 -1 (2900 2675)(2900 2625);
WIRE 16 -1 (2900 2575)(2650 2575);
WIRE 16 -1 (2900 2625)(2900 2575);
WIRE 16 -1 (2900 2525)(2650 2525);
WIRE 16 -1 (2900 2575)(2900 2525);
WIRE 16 -1 (2650 2475)(2900 2475);
WIRE 16 -1 (2900 2475)(2900 2525);
WIRE 16 -1 (2900 2425)(2650 2425);
WIRE 16 -1 (2900 2425)(2900 2475);
WIRE 16 -1 (2900 2375)(2650 2375);
WIRE 16 -1 (2900 2425)(2900 2375);
WIRE 16 -1 (2900 2325)(2650 2325);
WIRE 16 -1 (2900 2375)(2900 2325);
WIRE 16 -1 (2900 2275)(2650 2275);
WIRE 16 -1 (2900 2325)(2900 2275);
WIRE 16 -1 (2900 2225)(2650 2225);
WIRE 16 -1 (2900 2275)(2900 2225);
WIRE 16 -1 (2900 2175)(2650 2175);
WIRE 16 -1 (2900 2225)(2900 2175);
WIRE 16 -1 (2900 2125)(2650 2125);
WIRE 16 -1 (2900 2175)(2900 2125);
WIRE 16 -1 (2900 2075)(2650 2075);
WIRE 16 -1 (2900 2125)(2900 2075);
WIRE 16 -1 (2900 2025)(2650 2025);
WIRE 16 -1 (2900 2075)(2900 2025);
WIRE 16 -1 (2650 1975)(2900 1975);
WIRE 16 -1 (2900 2025)(2900 1975);
WIRE 16 -1 (2650 1925)(2900 1925);
WIRE 16 -1 (2900 1975)(2900 1925);
WIRE 16 -1 (2650 1875)(2900 1875);
WIRE 16 -1 (2900 1925)(2900 1875);
WIRE 16 -1 (2650 1825)(2900 1825);
WIRE 16 -1 (2900 1875)(2900 1825);
WIRE 16 -1 (2650 1775)(2900 1775);
WIRE 16 -1 (2900 1825)(2900 1775);
WIRE 16 -1 (2650 1725)(2900 1725);
WIRE 16 -1 (2900 1775)(2900 1725);
WIRE 16 -1 (2650 1675)(2900 1675);
WIRE 16 -1 (2900 1725)(2900 1675);
WIRE 16 -1 (2650 1625)(2900 1625);
WIRE 16 -1 (2900 1625)(2900 1675);
WIRE 16 -1 (2650 1575)(2900 1575);
WIRE 16 -1 (2900 1625)(2900 1575);
WIRE 16 -1 (2900 1525)(2650 1525);
WIRE 16 -1 (2900 1575)(2900 1525);
WIRE 16 -1 (2900 1475)(2650 1475);
WIRE 16 -1 (2900 1525)(2900 1475);
WIRE 16 -1 (2900 1425)(2650 1425);
WIRE 16 -1 (2900 1475)(2900 1425);
WIRE 16 -1 (2900 1375)(2650 1375);
WIRE 16 -1 (2900 1425)(2900 1375);
WIRE 16 -1 (2650 1325)(2900 1325);
WIRE 16 -1 (2900 1325)(2900 1375);
WIRE 16 -1 (2900 1275)(2650 1275);
WIRE 16 -1 (2900 1275)(2900 1325);
WIRE 16 -1 (2900 1225)(2650 1225);
WIRE 16 -1 (2900 1275)(2900 1225);
WIRE 16 -1 (2900 1175)(2650 1175);
WIRE 16 -1 (2900 1225)(2900 1175);
WIRE 16 -1 (2650 1125)(2900 1125);
WIRE 16 -1 (2900 1175)(2900 1125);
WIRE 16 -1 (2650 1075)(2900 1075);
WIRE 16 -1 (2900 1125)(2900 1075);
WIRE 16 -1 (2650 1025)(2900 1025);
WIRE 16 -1 (2900 1075)(2900 1025);
WIRE 16 -1 (2650 975)(2900 975);
WIRE 16 -1 (2900 1025)(2900 975);
WIRE 16 -1 (2650 925)(2900 925);
WIRE 16 -1 (2900 975)(2900 925);
WIRE 16 -1 (2650 875)(2900 875);
WIRE 16 -1 (2900 925)(2900 875);
WIRE 16 -1 (2650 825)(2900 825);
WIRE 16 -1 (2900 875)(2900 825);
WIRE 16 -1 (2650 775)(2900 775);
WIRE 16 -1 (2900 775)(2900 825);
WIRE 16 -1 (2650 725)(2900 725);
WIRE 16 -1 (2900 775)(2900 725);
WIRE 16 -1 (2900 675)(2650 675);
WIRE 16 -1 (2900 725)(2900 675);
WIRE 16 -1 (2900 625)(2650 625);
WIRE 16 -1 (2900 675)(2900 625);
WIRE 16 -1 (2900 575)(2650 575);
WIRE 16 -1 (2900 625)(2900 575);
WIRE 16 -1 (2900 525)(2650 525);
WIRE 16 -1 (2900 575)(2900 525);
WIRE 16 -1 (2650 475)(2900 475);
WIRE 16 -1 (2900 475)(2900 525);
WIRE 16 -1 (2900 425)(2650 425);
WIRE 16 -1 (2900 425)(2900 475);
WIRE 16 -1 (2900 375)(2650 375);
WIRE 16 -1 (2900 425)(2900 375);
WIRE 16 -1 (2900 325)(2650 325);
WIRE 16 -1 (2900 375)(2900 325);
WIRE 16 -1 (2650 275)(2900 275);
WIRE 16 -1 (2900 325)(2900 275);
WIRE 16 -1 (2650 225)(2900 225);
WIRE 16 -1 (2900 275)(2900 225);
WIRE 16 -1 (2650 175)(2900 175);
WIRE 16 -1 (2900 225)(2900 175);
WIRE 16 -1 (2900 175)(2900 125);
WIRE 16 -1 (2650 125)(2900 125);
WIRE 16 -1 (3275 3825)(3025 3825);
WIRE 16 -1 (3025 3825)(3025 3775);
WIRE 16 -1 (3275 3775)(3025 3775);
WIRE 16 -1 (3025 3775)(3025 3725);
WIRE 16 -1 (3275 3725)(3025 3725);
WIRE 16 -1 (3025 3725)(3025 3675);
WIRE 16 -1 (3275 3675)(3025 3675);
WIRE 16 -1 (3025 3675)(3025 3625);
WIRE 16 -1 (3275 3625)(3025 3625);
WIRE 16 -1 (3025 3625)(3025 3575);
WIRE 16 -1 (3275 3575)(3025 3575);
WIRE 16 -1 (3025 3575)(3025 3525);
WIRE 16 -1 (3275 3525)(3025 3525);
WIRE 16 -1 (3025 3525)(3025 3475);
WIRE 16 -1 (3275 3475)(3025 3475);
WIRE 16 -1 (3025 3475)(3025 3425);
WIRE 16 -1 (3275 3425)(3025 3425);
WIRE 16 -1 (3025 3425)(3025 3375);
WIRE 16 -1 (3275 3375)(3025 3375);
WIRE 16 -1 (3025 3375)(3025 3325);
WIRE 16 -1 (3275 3325)(3025 3325);
WIRE 16 -1 (3025 3325)(3025 3275);
WIRE 16 -1 (3275 3275)(3025 3275);
WIRE 16 -1 (3025 3275)(3025 3225);
WIRE 16 -1 (3275 3225)(3025 3225);
WIRE 16 -1 (3025 3225)(3025 3175);
WIRE 16 -1 (3275 3175)(3025 3175);
WIRE 16 -1 (3025 3175)(3025 3125);
WIRE 16 -1 (3025 3125)(3275 3125);
WIRE 16 -1 (3025 3125)(3025 3075);
WIRE 16 -1 (3025 3075)(3275 3075);
WIRE 16 -1 (3025 3075)(3025 3025);
WIRE 16 -1 (3025 3025)(3275 3025);
WIRE 16 -1 (3025 3025)(3025 2975);
WIRE 16 -1 (3025 2975)(3275 2975);
WIRE 16 -1 (3025 2975)(3025 2925);
WIRE 16 -1 (3025 2925)(3275 2925);
WIRE 16 -1 (3025 2925)(3025 2875);
WIRE 16 -1 (3025 2875)(3275 2875);
WIRE 16 -1 (3025 2875)(3025 2825);
WIRE 16 -1 (3025 2825)(3275 2825);
WIRE 16 -1 (3025 2825)(3025 2775);
WIRE 16 -1 (3025 2775)(3275 2775);
WIRE 16 -1 (3025 2775)(3025 2725);
WIRE 16 -1 (3025 2725)(3275 2725);
WIRE 16 -1 (3025 2725)(3025 2675);
WIRE 16 -1 (3025 2675)(3275 2675);
WIRE 16 -1 (3025 2675)(3025 2625);
WIRE 16 -1 (3025 2625)(3275 2625);
WIRE 16 -1 (3025 2625)(3025 2575);
WIRE 16 -1 (3025 2575)(3275 2575);
WIRE 16 -1 (3025 2575)(3025 2525);
WIRE 16 -1 (3025 2525)(3275 2525);
WIRE 16 -1 (3025 2525)(3025 2475);
WIRE 16 -1 (3025 2475)(3275 2475);
WIRE 16 -1 (3025 2475)(3025 2425);
WIRE 16 -1 (3025 2425)(3275 2425);
WIRE 16 -1 (3025 2425)(3025 2375);
WIRE 16 -1 (3025 2375)(3275 2375);
WIRE 16 -1 (3025 2375)(3025 2325);
WIRE 16 -1 (3025 2325)(3275 2325);
WIRE 16 -1 (3025 2325)(3025 2275);
WIRE 16 -1 (3025 2275)(3275 2275);
WIRE 16 -1 (3025 2275)(3025 2225);
WIRE 16 -1 (3025 2225)(3275 2225);
WIRE 16 -1 (3025 2225)(3025 2175);
WIRE 16 -1 (3025 2175)(3275 2175);
WIRE 16 -1 (3025 2175)(3025 2125);
WIRE 16 -1 (3275 2125)(3025 2125);
WIRE 16 -1 (3025 2125)(3025 2075);
WIRE 16 -1 (3025 2075)(3275 2075);
WIRE 16 -1 (3025 2025)(3275 2025);
WIRE 16 -1 (3025 2075)(3025 2025);
WIRE 16 -1 (3025 2025)(3025 1975);
WIRE 16 -1 (3025 1975)(3275 1975);
WIRE 16 -1 (3025 1975)(3025 1925);
WIRE 16 -1 (3025 1925)(3275 1925);
WIRE 16 -1 (3025 1925)(3025 1875);
WIRE 16 -1 (3025 1875)(3275 1875);
WIRE 16 -1 (3025 1875)(3025 1825);
WIRE 16 -1 (3025 1825)(3275 1825);
WIRE 16 -1 (3025 1825)(3025 1775);
WIRE 16 -1 (3025 1775)(3275 1775);
WIRE 16 -1 (3025 1775)(3025 1725);
WIRE 16 -1 (3025 1725)(3275 1725);
WIRE 16 -1 (3025 1725)(3025 1675);
WIRE 16 -1 (3025 1675)(3275 1675);
WIRE 16 -1 (3025 1675)(3025 1625);
WIRE 16 -1 (3025 1625)(3275 1625);
WIRE 16 -1 (3025 1625)(3025 1575);
WIRE 16 -1 (3025 1575)(3275 1575);
WIRE 16 -1 (3025 1575)(3025 1525);
WIRE 16 -1 (3025 1525)(3275 1525);
WIRE 16 -1 (3025 1525)(3025 1475);
WIRE 16 -1 (3025 1475)(3275 1475);
WIRE 16 -1 (3025 1475)(3025 1425);
WIRE 16 -1 (3025 1425)(3275 1425);
WIRE 16 -1 (3025 1425)(3025 1375);
WIRE 16 -1 (3025 1375)(3275 1375);
WIRE 16 -1 (3025 1375)(3025 1325);
WIRE 16 -1 (3025 1325)(3275 1325);
WIRE 16 -1 (3025 1325)(3025 1275);
WIRE 16 -1 (3025 1275)(3275 1275);
WIRE 16 -1 (3025 1275)(3025 1225);
WIRE 16 -1 (3025 1225)(3275 1225);
WIRE 16 -1 (3025 1225)(3025 1175);
WIRE 16 -1 (3025 1175)(3275 1175);
WIRE 16 -1 (3025 1175)(3025 1125);
WIRE 16 -1 (3275 1125)(3025 1125);
WIRE 16 -1 (3025 1125)(3025 1075);
WIRE 16 -1 (3025 1075)(3275 1075);
WIRE 16 -1 (3025 1075)(3025 1025);
WIRE 16 -1 (3025 1025)(3275 1025);
WIRE 16 -1 (3025 1025)(3025 975);
WIRE 16 -1 (3025 975)(3275 975);
WIRE 16 -1 (3025 975)(3025 925);
WIRE 16 -1 (3025 925)(3275 925);
WIRE 16 -1 (3025 925)(3025 875);
WIRE 16 -1 (3025 875)(3275 875);
WIRE 16 -1 (3025 875)(3025 825);
WIRE 16 -1 (3025 825)(3275 825);
WIRE 16 -1 (3025 825)(3025 775);
WIRE 16 -1 (3275 775)(3025 775);
WIRE 16 -1 (3025 775)(3025 725);
WIRE 16 -1 (3025 725)(3275 725);
WIRE 16 -1 (3025 725)(3025 675);
WIRE 16 -1 (3025 675)(3275 675);
WIRE 16 -1 (3025 675)(3025 625);
WIRE 16 -1 (3025 625)(3275 625);
WIRE 16 -1 (3025 625)(3025 575);
WIRE 16 -1 (3025 575)(3275 575);
WIRE 16 -1 (3025 575)(3025 525);
WIRE 16 -1 (3025 525)(3275 525);
WIRE 16 -1 (3025 525)(3025 475);
WIRE 16 -1 (3275 475)(3025 475);
WIRE 16 -1 (3025 475)(3025 425);
WIRE 16 -1 (3025 425)(3275 425);
WIRE 16 -1 (3025 425)(3025 375);
WIRE 16 -1 (3025 375)(3275 375);
WIRE 16 -1 (3025 375)(3025 325);
WIRE 16 -1 (3025 325)(3275 325);
WIRE 16 -1 (3025 325)(3025 275);
WIRE 16 -1 (3025 275)(3275 275);
WIRE 16 -1 (3025 275)(3025 225);
WIRE 16 -1 (3025 225)(3275 225);
WIRE 16 -1 (3025 225)(3025 175);
WIRE 16 -1 (3025 175)(3275 175);
WIRE 16 -1 (3025 175)(3025 125);
WIRE 16 -1 (3275 125)(3025 125);
WIRE 16 -1 (3025 125)(3025 75);
WIRE 16 -1 (3025 75)(3275 75);
WIRE 16 -1 (3025 75)(3025 25);
WIRE 16 -1 (3025 25)(3275 25);
DOT 1 (2900 225);
DOT 1 (0 2875);
DOT 1 (-150 2875);
DOT 1 (0 2325);
DOT 1 (-150 2175);
DOT 1 (3025 1175);
DOT 1 (0 1475);
DOT 1 (-3050 2125);
DOT 1 (-3050 1575);
DOT 1 (-150 925);
DOT 1 (3025 3775);
DOT 1 (2900 3775);
DOT 1 (3025 3675);
DOT 1 (3025 3725);
DOT 1 (3025 3625);
DOT 1 (3025 3575);
DOT 1 (3025 3525);
DOT 1 (2900 3725);
DOT 1 (2900 3675);
DOT 1 (2900 3625);
DOT 1 (2900 3575);
DOT 1 (2900 3525);
DOT 1 (3025 3425);
DOT 1 (3025 3475);
DOT 1 (3025 3325);
DOT 1 (3025 3375);
DOT 1 (3025 3275);
DOT 1 (2900 3475);
DOT 1 (2900 3425);
DOT 1 (2900 3375);
DOT 1 (2900 3275);
DOT 1 (2900 3325);
DOT 1 (3025 3225);
DOT 1 (3025 3175);
DOT 1 (3025 3125);
DOT 1 (3025 3025);
DOT 1 (3025 3075);
DOT 1 (2900 3225);
DOT 1 (2900 3175);
DOT 1 (2900 3125);
DOT 1 (2900 3075);
DOT 1 (2900 3025);
DOT 1 (3025 2975);
DOT 1 (3025 2925);
DOT 1 (3025 2875);
DOT 1 (3025 2825);
DOT 1 (3025 2775);
DOT 1 (2900 2975);
DOT 1 (2900 2925);
DOT 1 (2900 2875);
DOT 1 (2900 2775);
DOT 1 (2900 2825);
DOT 1 (3025 2725);
DOT 1 (3025 2675);
DOT 1 (3025 2625);
DOT 1 (3025 2525);
DOT 1 (3025 2575);
DOT 1 (2900 2725);
DOT 1 (2900 2675);
DOT 1 (2900 2625);
DOT 1 (2900 2575);
DOT 1 (2900 2525);
DOT 1 (3025 2475);
DOT 1 (3025 2425);
DOT 1 (3025 2375);
DOT 1 (3025 2325);
DOT 1 (3025 2275);
DOT 1 (2900 2475);
DOT 1 (2900 2425);
DOT 1 (2900 2375);
DOT 1 (2900 2325);
DOT 1 (2900 2275);
DOT 1 (2900 2225);
DOT 1 (3025 2225);
DOT 1 (3025 2125);
DOT 1 (3025 2175);
DOT 1 (3025 2075);
DOT 1 (3025 2025);
DOT 1 (2900 2175);
DOT 1 (2900 2125);
DOT 1 (2900 2075);
DOT 1 (2900 2025);
DOT 1 (2900 1975);
DOT 1 (3025 1975);
DOT 1 (3025 1875);
DOT 1 (3025 1925);
DOT 1 (3025 1825);
DOT 1 (3025 1775);
DOT 1 (3025 1725);
DOT 1 (2900 1925);
DOT 1 (2900 1875);
DOT 1 (2900 1825);
DOT 1 (2900 1775);
DOT 1 (2900 1725);
DOT 1 (3025 1625);
DOT 1 (3025 1675);
DOT 1 (3025 1575);
DOT 1 (3025 1525);
DOT 1 (3025 1475);
DOT 1 (2900 1675);
DOT 1 (2900 1625);
DOT 1 (2900 1575);
DOT 1 (2900 1525);
DOT 1 (2900 1475);
DOT 1 (3025 1375);
DOT 1 (3025 1425);
DOT 1 (3025 1325);
DOT 1 (3025 1275);
DOT 1 (3025 1225);
DOT 1 (2900 1425);
DOT 1 (2900 1375);
DOT 1 (2900 1325);
DOT 1 (2900 1275);
DOT 1 (2900 1225);
DOT 1 (3025 1125);
DOT 1 (3025 1075);
DOT 1 (3025 975);
DOT 1 (3025 1025);
DOT 1 (2900 1175);
DOT 1 (2900 1125);
DOT 1 (2900 1075);
DOT 1 (2900 1025);
DOT 1 (2900 975);
DOT 1 (3025 925);
DOT 1 (3025 875);
DOT 1 (3025 825);
DOT 1 (3025 775);
DOT 1 (3025 725);
DOT 1 (2900 925);
DOT 1 (2900 875);
DOT 1 (2900 825);
DOT 1 (2900 725);
DOT 1 (2900 775);
DOT 1 (3025 675);
DOT 1 (3025 625);
DOT 1 (3025 575);
DOT 1 (3025 475);
DOT 1 (3025 525);
DOT 1 (2900 675);
DOT 1 (2900 625);
DOT 1 (2900 575);
DOT 1 (2900 525);
DOT 1 (2900 475);
DOT 1 (3025 425);
DOT 1 (3025 375);
DOT 1 (3025 325);
DOT 1 (3025 275);
DOT 1 (3025 225);
DOT 1 (2900 425);
DOT 1 (2900 375);
DOT 1 (2900 325);
DOT 1 (2900 275);
DOT 1 (3025 175);
DOT 1 (3025 125);
DOT 1 (3025 75);
DOT 1 (3025 25);
DOT 1 (3025 -25);
DOT 1 (2900 175);
DOT 1 (2900 75);
DOT 1 (2900 125);
DOT 1 (0 3775);
DOT 1 (-150 3775);
DOT 1 (0 3725);
DOT 1 (0 3675);
DOT 1 (0 3625);
DOT 1 (0 3575);
DOT 1 (0 3525);
DOT 1 (0 3425);
DOT 1 (0 3475);
DOT 1 (0 3325);
DOT 1 (0 3275);
DOT 1 (0 3375);
DOT 1 (-150 3525);
DOT 1 (-150 3725);
DOT 1 (-150 3675);
DOT 1 (-150 3625);
DOT 1 (-150 3575);
DOT 1 (-150 3275);
DOT 1 (-150 3425);
DOT 1 (-150 3475);
DOT 1 (-150 3375);
DOT 1 (-150 3325);
DOT 1 (0 3225);
DOT 1 (0 3175);
DOT 1 (0 3125);
DOT 1 (0 3025);
DOT 1 (0 3075);
DOT 1 (0 2975);
DOT 1 (0 2925);
DOT 1 (0 2825);
DOT 1 (0 2775);
DOT 1 (-150 3075);
DOT 1 (-150 3175);
DOT 1 (-150 3225);
DOT 1 (-150 3125);
DOT 1 (-150 3025);
DOT 1 (-150 2775);
DOT 1 (-150 2975);
DOT 1 (-150 2925);
DOT 1 (-150 2825);
DOT 1 (0 2725);
DOT 1 (0 2675);
DOT 1 (0 2625);
DOT 1 (0 2525);
DOT 1 (0 2575);
DOT 1 (0 2475);
DOT 1 (0 2425);
DOT 1 (0 2375);
DOT 1 (0 2275);
DOT 1 (-150 2575);
DOT 1 (-150 2675);
DOT 1 (-150 2725);
DOT 1 (-150 2625);
DOT 1 (-150 2525);
DOT 1 (-150 2275);
DOT 1 (-150 2475);
DOT 1 (-150 2425);
DOT 1 (-150 2375);
DOT 1 (-150 2325);
DOT 1 (-150 2225);
DOT 1 (0 2225);
DOT 1 (0 2175);
DOT 1 (0 2125);
DOT 1 (0 2075);
DOT 1 (0 2025);
DOT 1 (0 1975);
DOT 1 (0 1875);
DOT 1 (0 1925);
DOT 1 (0 1825);
DOT 1 (0 1725);
DOT 1 (0 1775);
DOT 1 (-150 2125);
DOT 1 (-150 2075);
DOT 1 (-150 2025);
DOT 1 (-150 1975);
DOT 1 (-150 1775);
DOT 1 (-150 1875);
DOT 1 (-150 1925);
DOT 1 (-150 1825);
DOT 1 (-150 1725);
DOT 1 (0 1675);
DOT 1 (0 1625);
DOT 1 (0 1575);
DOT 1 (0 1525);
DOT 1 (0 1375);
DOT 1 (0 1425);
DOT 1 (0 1325);
DOT 1 (0 1275);
DOT 1 (0 1225);
DOT 1 (-150 1475);
DOT 1 (-150 1675);
DOT 1 (-150 1625);
DOT 1 (-150 1575);
DOT 1 (-150 1525);
DOT 1 (-150 1225);
DOT 1 (-150 1375);
DOT 1 (-150 1425);
DOT 1 (-150 1325);
DOT 1 (-150 1275);
DOT 1 (0 1175);
DOT 1 (0 1125);
DOT 1 (0 1075);
DOT 1 (0 975);
DOT 1 (0 1025);
DOT 1 (0 925);
DOT 1 (0 875);
DOT 1 (0 825);
DOT 1 (0 775);
DOT 1 (0 725);
DOT 1 (-150 975);
DOT 1 (-150 1125);
DOT 1 (-150 1175);
DOT 1 (-150 1075);
DOT 1 (-150 1025);
DOT 1 (-150 725);
DOT 1 (-150 875);
DOT 1 (-150 825);
DOT 1 (-150 775);
DOT 1 (0 675);
DOT 1 (0 625);
DOT 1 (0 575);
DOT 1 (0 475);
DOT 1 (0 525);
DOT 1 (0 425);
DOT 1 (0 375);
DOT 1 (0 325);
DOT 1 (0 275);
DOT 1 (0 225);
DOT 1 (-150 475);
DOT 1 (-150 625);
DOT 1 (-150 675);
DOT 1 (-150 575);
DOT 1 (-150 525);
DOT 1 (-150 225);
DOT 1 (-150 425);
DOT 1 (-150 375);
DOT 1 (-150 325);
DOT 1 (-150 275);
DOT 1 (-3050 3775);
DOT 1 (-3050 3675);
DOT 1 (-3050 3725);
DOT 1 (-3050 3625);
DOT 1 (-3050 3575);
DOT 1 (-3050 3525);
DOT 1 (-3050 3425);
DOT 1 (-3050 3475);
DOT 1 (-3050 3325);
DOT 1 (-3050 3275);
DOT 1 (-3050 3375);
DOT 1 (-3050 3225);
DOT 1 (-3050 3175);
DOT 1 (-3050 3125);
DOT 1 (-3050 3025);
DOT 1 (-3050 3075);
DOT 1 (-3050 2975);
DOT 1 (-3050 2925);
DOT 1 (-3050 2875);
DOT 1 (-3050 2825);
DOT 1 (-3050 2775);
DOT 1 (-3050 2725);
DOT 1 (-3050 2675);
DOT 1 (-3050 2625);
DOT 1 (-3050 2525);
DOT 1 (-3050 2575);
DOT 1 (-3050 2475);
DOT 1 (-3050 2425);
DOT 1 (-3050 2375);
DOT 1 (-3050 2325);
DOT 1 (-3050 2275);
DOT 1 (-3050 2225);
DOT 1 (-3050 2175);
DOT 1 (-3050 2075);
DOT 1 (-3050 2025);
DOT 1 (-3050 1975);
DOT 1 (-3050 1875);
DOT 1 (-3050 1925);
DOT 1 (-3050 1825);
DOT 1 (-3050 1775);
DOT 1 (-3050 1725);
DOT 1 (-3050 1625);
DOT 1 (-3050 1675);
DOT 1 (-3050 1525);
DOT 1 (-3050 1475);
DOT 1 (-3050 1375);
DOT 1 (-3050 1425);
DOT 1 (-3050 1325);
DOT 1 (-3050 1275);
DOT 1 (-3050 1225);
DOT 1 (-3050 1175);
DOT 1 (-3050 1125);
DOT 1 (-3050 1075);
DOT 1 (-3050 975);
DOT 1 (-3050 1025);
DOT 1 (-3050 925);
DOT 1 (-3050 875);
DOT 1 (-3050 825);
DOT 1 (-3050 775);
DOT 1 (-3050 725);
DOT 1 (-3050 675);
DOT 1 (-3050 625);
DOT 1 (-3050 575);
DOT 1 (-3050 475);
DOT 1 (-3050 525);
DOT 1 (-3050 425);
DOT 1 (-3050 375);
DOT 1 (-3050 325);
DOT 1 (-3050 275);
DOT 1 (-3050 225);
DOT 1 (0 125);
DOT 1 (0 175);
DOT 1 (0 75);
DOT 1 (0 25);
DOT 1 (0 -25);
DOT 1 (0 -75);
DOT 1 (0 -125);
DOT 1 (-150 175);
DOT 1 (-150 -25);
DOT 1 (-150 125);
DOT 1 (-150 75);
DOT 1 (-150 25);
DOT 1 (-150 -75);
DOT 1 (-150 -125);
DOT 1 (-3050 75);
DOT 1 (-3050 125);
DOT 1 (-3050 175);
DOT 1 (-3050 25);
DOT 1 (-3050 -25);
DOT 1 (-3050 -75);
DOT 1 (-3050 -125);
QUIT
